G04 ================== begin FILE IDENTIFICATION RECORD ==================*
G04 Layout Name:  9052_F0T_PDB_Converter_Brick_F_V03_1208_1600.brd*
G04 Film Name:    smb*
G04 File Format:  Gerber RS274X*
G04 File Origin:  Cadence Allegro 17.2-S081*
G04 Origin Date:  Wed Dec 21 09:54:58 2022*
G04 *
G04 Layer:  DRAWING FORMAT/TITLE_BLOCK_A*
G04 Layer:  DRAWING FORMAT/TITLE_BLOCK*
G04 Layer:  VIA CLASS/SOLDERMASK_BOTTOM*
G04 Layer:  PIN/SOLDERMASK_BOTTOM*
G04 Layer:  PACKAGE GEOMETRY/SOLDERMASK_BOTTOM*
G04 Layer:  MANUFACTURING/PHOTOPLOT_OUTLINE*
G04 Layer:  DRAWING FORMAT/TITLE_DATA_SMB*
G04 Layer:  BOARD GEOMETRY/SOLDERMASK_BOTTOM*
G04 *
G04 Offset:    (0.00 0.00)*
G04 Mirror:    No*
G04 Mode:      Positive*
G04 Rotation:  0*
G04 FullContactRelief:  No*
G04 UndefLineWidth:     6.00*
G04 ================== end FILE IDENTIFICATION RECORD ====================*
%FSLAX25Y25*MOIN*%
%IR0*IPPOS*OFA0.00000B0.00000*MIA0B0*SFA1.00000B1.00000*%
%ADD55R,.103X.071*%
%AMMACRO23*
4,1,8,.03153,.06499,
-.03153,.06499,
-.03153,.01768,
.01571,.01768,
.01571,-.01769,
-.03153,-.01769,
-.03153,-.06499,
.03153,-.06499,
.03153,.06499,
0.0*
%
%ADD23MACRO23*%
%ADD16C,.03*%
%ADD54C,.07*%
%ADD12C,.062*%
%ADD13C,.054*%
%ADD38C,.064*%
%ADD31C,.056*%
%ADD10O,1.264X.398*%
%ADD63R,.134X.099*%
%ADD29C,.066*%
%ADD46C,.085*%
%ADD53R,.07X.07*%
%ADD42C,.06415*%
%ADD34C,.097*%
%ADD14R,.054X.054*%
%ADD39R,.064X.064*%
%ADD28R,.066X.066*%
%ADD43R,.06415X.06415*%
%ADD41R,.097X.097*%
%AMMACRO37*
4,1,28,-.00589,.01192,
-.006913,.011842,
-.007907,.011587,
-.008842,.011163,
-.009688,.010584,
-.010422,.009866,
-.011019,.009032,
-.011463,.008107,
-.011739,.007119,
-.01184,.006097,
-.01184,.00603,
-.01184,-.00148,
-.00948,-.00148,
-.00948,-.01191,
.00948,-.01191,
.00948,-.00148,
.01184,-.00148,
.01184,.00603,
.011751,.007052,
.011486,.008044,
.011053,.008974,
.010465,.009815,
.00974,.010541,
.0089,.01113,
.00797,.011564,
.006979,.01183,
.005957,.01192,
.00589,.01192,
-.00589,.01192,
0.0*
%
%ADD37MACRO37*%
%AMMACRO20*
4,1,28,.01192,.00589,
.011842,.006913,
.011587,.007907,
.011163,.008842,
.010584,.009688,
.009866,.010422,
.009032,.011019,
.008107,.011463,
.007119,.011739,
.006097,.01184,
.00603,.01184,
-.00148,.01184,
-.00148,.00948,
-.01191,.00948,
-.01191,-.00948,
-.00148,-.00948,
-.00148,-.01184,
.00603,-.01184,
.007052,-.011751,
.008044,-.011486,
.008974,-.011053,
.009815,-.010465,
.010541,-.00974,
.01113,-.0089,
.011564,-.00797,
.01183,-.006979,
.01192,-.005957,
.01192,-.00589,
.01192,.00589,
0.0*
%
%ADD20MACRO20*%
%AMMACRO36*
4,1,28,.0059,-.01191,
.006923,-.01183,
.007916,-.011573,
.00885,-.011148,
.009696,-.010567,
.010428,-.009849,
.011024,-.009013,
.011466,-.008088,
.011741,-.007099,
.01184,-.006078,
.01184,-.00602,
.01184,.00149,
.00948,.00149,
.00948,.01192,
-.00948,.01192,
-.00948,.00149,
-.01184,.00149,
-.01184,-.00602,
-.011751,-.007042,
-.011486,-.008033,
-.011053,-.008964,
-.010465,-.009805,
-.00974,-.010531,
-.0089,-.01112,
-.007971,-.011554,
-.00698,-.01182,
-.005958,-.01191,
-.0059,-.01191,
.0059,-.01191,
0.0*
%
%ADD36MACRO36*%
%AMMACRO19*
4,1,28,-.01191,-.0059,
-.01183,-.006923,
-.011573,-.007916,
-.011148,-.00885,
-.010567,-.009696,
-.009849,-.010428,
-.009013,-.011024,
-.008088,-.011466,
-.007099,-.011741,
-.006078,-.01184,
-.00602,-.01184,
.00149,-.01184,
.00149,-.00948,
.01192,-.00948,
.01192,.00948,
.00149,.00948,
.00149,.01184,
-.00602,.01184,
-.007042,.011751,
-.008033,.011486,
-.008964,.011053,
-.009805,.010465,
-.010531,.00974,
-.01112,.0089,
-.011554,.007971,
-.01182,.00698,
-.01191,.005958,
-.01191,.0059,
-.01191,-.0059,
0.0*
%
%ADD19MACRO19*%
%AMMACRO22*
4,1,8,-.03153,-.06499,
.03153,-.06499,
.03153,-.01768,
-.01571,-.01768,
-.01571,.01769,
.03153,.01769,
.03153,.06499,
-.03153,.06499,
-.03153,-.06499,
0.0*
%
%ADD22MACRO22*%
%ADD40R,.024X.022*%
%ADD61R,.022X.024*%
%ADD44R,.04X.036*%
%ADD59R,.036X.032*%
%ADD57R,.036X.04*%
%ADD48R,.021X.028*%
%ADD21R,.048X.02*%
%ADD58R,.032X.036*%
%ADD62R,.058X.03*%
%ADD52R,.018X.06*%
%ADD49R,.022X.056*%
%ADD17C,.241*%
%ADD51R,.066X.05*%
%ADD35C,.26*%
%ADD18R,.054X.044*%
%ADD11C,.107*%
%ADD50R,.026X.072*%
%ADD47R,.018X.063*%
%ADD30C,.118*%
%ADD27C,.127*%
%ADD24C,.145*%
%ADD60R,.038X.036*%
%ADD64C,.319*%
%ADD15C,.176*%
%ADD45R,.058X.048*%
%ADD56R,.048X.058*%
%AMMACRO33*
4,1,28,.00589,-.01192,
.006913,-.011842,
.007907,-.011587,
.008842,-.011163,
.009688,-.010584,
.010422,-.009866,
.011019,-.009032,
.011463,-.008107,
.011739,-.007119,
.01184,-.006097,
.01184,-.00603,
.01184,.00148,
.00948,.00148,
.00948,.01191,
-.00948,.01191,
-.00948,.00148,
-.01184,.00148,
-.01184,-.00603,
-.011751,-.007052,
-.011486,-.008044,
-.011053,-.008974,
-.010465,-.009815,
-.00974,-.010541,
-.0089,-.01113,
-.00797,-.011564,
-.006979,-.01183,
-.005957,-.01192,
-.00589,-.01192,
.00589,-.01192,
0.0*
%
%ADD33MACRO33*%
%AMMACRO26*
4,1,28,-.01192,-.00589,
-.011842,-.006913,
-.011587,-.007907,
-.011163,-.008842,
-.010584,-.009688,
-.009866,-.010422,
-.009032,-.011019,
-.008107,-.011463,
-.007119,-.011739,
-.006097,-.01184,
-.00603,-.01184,
.00148,-.01184,
.00148,-.00948,
.01191,-.00948,
.01191,.00948,
.00148,.00948,
.00148,.01184,
-.00603,.01184,
-.007052,.011751,
-.008044,.011486,
-.008974,.011053,
-.009815,.010465,
-.010541,.00974,
-.01113,.0089,
-.011564,.00797,
-.01183,.006979,
-.01192,.005957,
-.01192,.00589,
-.01192,-.00589,
0.0*
%
%ADD26MACRO26*%
%AMMACRO32*
4,1,28,-.0059,.01191,
-.006923,.01183,
-.007916,.011573,
-.00885,.011148,
-.009696,.010567,
-.010428,.009849,
-.011024,.009013,
-.011466,.008088,
-.011741,.007099,
-.01184,.006078,
-.01184,.00602,
-.01184,-.00149,
-.00948,-.00149,
-.00948,-.01192,
.00948,-.01192,
.00948,-.00149,
.01184,-.00149,
.01184,.00602,
.011751,.007042,
.011486,.008033,
.011053,.008964,
.010465,.009805,
.00974,.010531,
.0089,.01112,
.007971,.011554,
.00698,.01182,
.005958,.01191,
.0059,.01191,
-.0059,.01191,
0.0*
%
%ADD32MACRO32*%
%AMMACRO25*
4,1,28,.01191,.0059,
.01183,.006923,
.011573,.007916,
.011148,.00885,
.010567,.009696,
.009849,.010428,
.009013,.011024,
.008088,.011466,
.007099,.011741,
.006078,.01184,
.00602,.01184,
-.00149,.01184,
-.00149,.00948,
-.01192,.00948,
-.01192,-.00948,
-.00149,-.00948,
-.00149,-.01184,
.00602,-.01184,
.007042,-.011751,
.008033,-.011486,
.008964,-.011053,
.009805,-.010465,
.010531,-.00974,
.01112,-.0089,
.011554,-.007971,
.01182,-.00698,
.01191,-.005958,
.01191,-.0059,
.01191,.0059,
0.0*
%
%ADD25MACRO25*%
%ADD65C,.02*%
%ADD66C,.006*%
G75*
%LPD*%
G75*
G36*
G01X216900Y26000D02*
G03I-5900J0D01*
G37*
G36*
G01X960450Y77250D02*
G03I-5900J0D01*
G37*
G36*
G01X1161250Y561140D02*
G03I-5900J0D01*
G37*
G54D10*
X74804Y47244D03*
Y535433D03*
X468504Y47244D03*
X862205D03*
X945193Y228000D03*
X987193Y542500D03*
X1196858Y57480D03*
Y521260D03*
G54D11*
X19922Y214173D03*
Y367716D03*
G54D20*
X154983Y331000D03*
Y335500D03*
Y350500D03*
Y346500D03*
X181357Y223523D03*
X215983Y309500D03*
X224483D03*
X233483D03*
X390483D03*
X372983D03*
X381483D03*
X427002Y457500D03*
X530983Y310500D03*
X548983D03*
X539983D03*
X578483Y457500D03*
X688464Y310500D03*
X697464D03*
X706464D03*
X734983Y338500D03*
Y328500D03*
X747983Y338500D03*
Y334500D03*
Y324500D03*
Y328500D03*
Y342500D03*
Y347700D03*
Y353200D03*
Y361500D03*
X800483Y357000D03*
Y362000D03*
X778483Y369500D03*
X826983Y334000D03*
X837483Y323500D03*
Y328000D03*
X940679Y315385D03*
X941179Y347885D03*
X1037483Y139500D03*
X1049483Y125500D03*
X1062983Y130500D03*
Y134000D03*
X1049483Y133600D03*
X1073483Y114000D03*
X1090983Y167500D03*
Y174500D03*
Y164000D03*
Y171000D03*
X1080326Y363443D03*
X1103483Y165000D03*
Y168500D03*
X1140483Y196500D03*
Y200500D03*
G54D30*
X211000Y26000D03*
X954550Y77250D03*
X1155350Y561140D03*
G54D21*
X129370Y414500D03*
X150630D03*
X760280Y336484D03*
Y359516D03*
Y356957D03*
Y354398D03*
Y351839D03*
Y349280D03*
Y346720D03*
Y344161D03*
Y341602D03*
Y339043D03*
X782720Y336484D03*
Y339043D03*
Y341602D03*
Y344161D03*
Y346720D03*
Y349280D03*
Y351839D03*
Y354398D03*
Y356957D03*
Y359516D03*
G54D12*
X38780Y232598D03*
Y239291D03*
Y252598D03*
Y259291D03*
Y272598D03*
Y279291D03*
Y292598D03*
Y299291D03*
X48780Y232598D03*
Y239291D03*
Y252598D03*
Y259291D03*
Y272598D03*
Y279291D03*
Y292598D03*
Y299291D03*
G54D40*
X247441Y303575D03*
Y300425D03*
X404821Y303575D03*
Y300425D03*
X562402Y303575D03*
Y300425D03*
X719883Y303575D03*
Y300425D03*
G54D22*
X127795Y414500D03*
G54D31*
X208071Y267204D03*
X200197D03*
X215945D03*
X231693D03*
X223819D03*
X239567D03*
X247441D03*
X357677D03*
X365551D03*
X373425D03*
X389173D03*
X381299D03*
X404921D03*
X397047D03*
X523032D03*
X515158D03*
X530906D03*
X538780D03*
X546654D03*
X562402D03*
X554528D03*
X680513D03*
X672639D03*
X688387D03*
X704135D03*
X696261D03*
X712009D03*
X719883D03*
G54D13*
X33780Y334724D03*
Y324724D03*
X38780Y319724D03*
Y329724D03*
Y339724D03*
X33780Y344724D03*
X38780Y349724D03*
X48780Y319724D03*
Y329724D03*
Y339724D03*
X43780Y314724D03*
Y324724D03*
Y334724D03*
X48780Y349724D03*
X43780Y344724D03*
G54D32*
X208071Y303484D03*
X239567D03*
X223819Y458484D03*
X251500Y303484D03*
X365551D03*
X381299Y458484D03*
X412019Y450484D03*
X432019Y457484D03*
X523032Y303484D03*
X538780Y458484D03*
X569500Y450484D03*
X589500Y451984D03*
X680513Y303484D03*
X696261Y458484D03*
X724000Y303484D03*
X826000Y275984D03*
X831000D03*
X816000D03*
X821000D03*
X806500Y282484D03*
X819500Y326484D03*
X827500D03*
X821500Y357984D03*
X846000Y275984D03*
X851000D03*
X856000D03*
X841000D03*
X836000D03*
X864500Y355984D03*
X843000Y359984D03*
X875000Y296984D03*
X880000D03*
X870000D03*
X888000Y280984D03*
X877500D03*
X884000D03*
X894500D03*
X875000Y309984D03*
X880000D03*
X870000D03*
X878000Y355984D03*
X869000D03*
X898500Y280984D03*
X909500Y297484D03*
X914500D03*
X909000Y280984D03*
X905000D03*
X915500D03*
X903500Y325484D03*
X909500Y335484D03*
X912500Y325484D03*
X915500Y360984D03*
X920000D03*
X947000Y280984D03*
X940000D03*
X947000Y290984D03*
X940000D03*
X933000D03*
X938000Y360984D03*
X1070000Y188984D03*
X1077000Y184484D03*
X1082500D03*
X1073500Y188984D03*
X1110000Y144984D03*
X1141500Y117484D03*
X1132000Y180484D03*
G54D50*
X865000Y338900D03*
Y318100D03*
X880000Y338900D03*
X875000D03*
X870000D03*
Y318100D03*
X875000D03*
X880000D03*
G54D41*
X253819Y477204D03*
X411299D03*
X568780D03*
X726261D03*
G54D14*
X33780Y314724D03*
G54D23*
X152205Y414500D03*
G54D33*
X208071Y300517D03*
X239567D03*
X223819Y455517D03*
X251500Y300517D03*
X365551D03*
X381299Y455517D03*
X412019Y447517D03*
X432019Y454517D03*
X523032Y300517D03*
X538780Y455517D03*
X569500Y447517D03*
X589500Y449017D03*
X680513Y300517D03*
X696261Y455517D03*
X724000Y300517D03*
X826000Y273017D03*
X831000D03*
X816000D03*
X821000D03*
X806500Y279517D03*
X819500Y323517D03*
X827500D03*
X821500Y355017D03*
X846000Y273017D03*
X851000D03*
X856000D03*
X841000D03*
X836000D03*
X864500Y353017D03*
X843000Y357017D03*
X888000Y278017D03*
X877500D03*
X884000D03*
X894500D03*
X875000Y307017D03*
X880000D03*
X875000Y294017D03*
X880000D03*
X870000Y307017D03*
Y294017D03*
X878000Y353017D03*
X869000D03*
X898500Y278017D03*
X909000D03*
X905000D03*
X915500D03*
X909500Y294517D03*
X914500D03*
X903500Y322517D03*
X909500Y332517D03*
X912500Y322517D03*
X915500Y358017D03*
X920000D03*
X947000Y278017D03*
X940000D03*
X947000Y288017D03*
X940000D03*
X933000D03*
X938000Y358017D03*
X1070000Y186017D03*
X1077000Y181517D03*
X1082500D03*
X1073500Y186017D03*
X1110000Y142017D03*
X1141500Y114517D03*
X1132000Y177517D03*
G54D15*
X60630Y99724D03*
Y482205D03*
X108858Y99724D03*
Y482205D03*
G54D60*
X1086343Y368243D03*
Y359643D03*
Y415743D03*
Y407143D03*
G54D24*
X175000Y100500D03*
X877510Y558620D03*
X964460Y16950D03*
G54D51*
X866000Y370200D03*
Y381800D03*
X847000Y370200D03*
Y381800D03*
X856500Y370200D03*
Y381800D03*
X885000Y370200D03*
Y381800D03*
X894500Y370200D03*
Y381800D03*
X875500Y370200D03*
Y381800D03*
X904000Y370200D03*
Y381800D03*
X923500Y370200D03*
Y381800D03*
X913500Y370200D03*
Y381800D03*
X933000Y370200D03*
Y381800D03*
X942500Y370200D03*
Y381800D03*
X952000Y370200D03*
Y381800D03*
G54D42*
X296752Y129685D03*
Y139685D03*
Y149685D03*
X331752Y129685D03*
X306752D03*
X331752Y139685D03*
Y149685D03*
Y159685D03*
X306752Y139685D03*
Y149685D03*
Y159685D03*
X341752Y129685D03*
Y139685D03*
Y149685D03*
Y159685D03*
X376752Y129685D03*
X366752D03*
X376752Y139685D03*
Y149685D03*
Y159685D03*
X366752Y139685D03*
Y149685D03*
Y159685D03*
X411752Y129685D03*
X401752D03*
X411752Y139685D03*
Y149685D03*
Y159685D03*
X401752Y139685D03*
Y149685D03*
Y159685D03*
X446752Y129685D03*
X436752D03*
X446752Y139685D03*
Y149685D03*
Y159685D03*
X436752Y139685D03*
Y149685D03*
Y159685D03*
X481752Y129685D03*
X471752D03*
X481752Y139685D03*
Y149685D03*
Y159685D03*
X471752Y139685D03*
Y149685D03*
Y159685D03*
X712559Y129408D03*
Y119408D03*
Y149408D03*
Y139408D03*
X722559Y129408D03*
Y119408D03*
X747559Y129408D03*
Y119408D03*
X722559Y149408D03*
Y139408D03*
X747559Y149408D03*
Y139408D03*
X757559Y129408D03*
Y119408D03*
Y149408D03*
Y139408D03*
X782559Y129408D03*
Y119408D03*
X792559Y129408D03*
Y119408D03*
X782559Y149408D03*
Y139408D03*
X792559Y149408D03*
Y139408D03*
X812559Y119408D03*
Y129408D03*
X822559Y119408D03*
Y129408D03*
X832559Y119408D03*
Y129408D03*
X812559Y139408D03*
Y149408D03*
X822559Y139408D03*
Y149408D03*
X832559Y139408D03*
X852559Y129408D03*
Y119408D03*
X862559Y129408D03*
Y119408D03*
X852559Y149408D03*
Y139408D03*
X862559Y149408D03*
Y139408D03*
X887559Y129408D03*
Y119408D03*
Y149408D03*
Y139408D03*
X897559Y129408D03*
Y119408D03*
X922559Y129408D03*
Y119408D03*
X897559Y149408D03*
Y139408D03*
X922559Y149408D03*
Y139408D03*
X932559Y129408D03*
Y119408D03*
Y149408D03*
Y139408D03*
X1226024Y221929D03*
X1236024D03*
X1246024D03*
X1226024Y231929D03*
X1236024D03*
X1246024D03*
X1226024Y256929D03*
X1236024D03*
X1246024D03*
X1226024Y266929D03*
X1236024D03*
X1246024D03*
X1236024Y286929D03*
X1246024D03*
X1226024Y306929D03*
X1236024D03*
X1246024D03*
X1226024Y316929D03*
X1236024D03*
X1246024D03*
X1226024Y341929D03*
X1236024D03*
X1246024D03*
X1226024Y351929D03*
X1236024D03*
X1246024D03*
X1256024Y221929D03*
Y231929D03*
Y256929D03*
Y266929D03*
Y286929D03*
Y306929D03*
Y316929D03*
Y341929D03*
Y351929D03*
G54D25*
X181388Y227723D03*
X215984Y300500D03*
X224484D03*
X233484D03*
X224484Y305000D03*
X233484D03*
X215984D03*
X390484Y300500D03*
X372984D03*
X381484D03*
X390484Y305000D03*
X381484D03*
X372984D03*
X421503Y433500D03*
X530984Y300500D03*
Y305500D03*
X539984Y300500D03*
X548984D03*
X539984Y305500D03*
X548984D03*
X578984Y433500D03*
X688465Y300500D03*
X697465D03*
X706465D03*
X688465Y305500D03*
X697465D03*
X706465D03*
X800484Y330000D03*
Y335000D03*
Y341000D03*
Y346500D03*
Y352000D03*
X811484Y341000D03*
Y357000D03*
Y362000D03*
X837484Y332500D03*
X940484Y306500D03*
X940680Y310885D03*
X941180Y352385D03*
X1049484Y129000D03*
X1060484Y142000D03*
X1049484Y137500D03*
X1044984Y151000D03*
X1080327Y359443D03*
X1103484Y180000D03*
Y183500D03*
X1140779Y143734D03*
X1153484Y154000D03*
G54D52*
X933357Y322596D03*
X935916D03*
X938476D03*
X941035D03*
Y340174D03*
X938476D03*
X935916D03*
X933357D03*
G54D61*
X1092425Y354000D03*
X1095575D03*
X1092425Y401500D03*
X1095575D03*
G54D43*
X296752Y159685D03*
X832559Y149408D03*
X1226024Y286929D03*
G54D34*
X193819Y477204D03*
X223819D03*
X351299D03*
X381299D03*
X508780D03*
X538780D03*
X666261D03*
X696261D03*
G54D16*
X60600Y335500D03*
X68403Y323700D03*
X69745Y350042D03*
X154840Y244730D03*
X128500Y426000D03*
X178265Y213443D03*
X175976Y218775D03*
X166068Y238749D03*
X173869Y228168D03*
X178329Y232900D03*
X160017Y237764D03*
X185954Y226083D03*
X171302Y333471D03*
X163247Y335500D03*
X179400Y326800D03*
X183539Y518000D03*
Y498000D03*
X171939D03*
Y518000D03*
X246000Y238500D03*
X231539Y518000D03*
Y498000D03*
X219939D03*
Y518000D03*
X267939Y498000D03*
Y518000D03*
X279539D03*
Y498000D03*
X329419D03*
Y518000D03*
X341019D03*
Y498000D03*
X369925Y287357D03*
X378479Y314111D03*
X389019Y518000D03*
Y498000D03*
X377419D03*
Y518000D03*
X402000Y238000D03*
X398500Y247000D03*
X421594Y438360D03*
X432000Y427600D03*
X437019Y518000D03*
Y498000D03*
X425419D03*
Y518000D03*
X498500Y498000D03*
Y518000D03*
X486900Y498000D03*
Y518000D03*
X535000Y295900D03*
X534900Y498000D03*
Y518000D03*
X544500Y450575D03*
X546500Y498000D03*
Y518000D03*
X575925Y425500D03*
X578984Y438000D03*
X594500Y498000D03*
Y518000D03*
X582900D03*
Y498000D03*
X605600Y448446D03*
X647975Y37000D03*
X660200Y56800D03*
X652300D03*
X655981Y518000D03*
Y498000D03*
X644381Y518000D03*
Y498000D03*
X684525Y32500D03*
X690075Y39500D03*
X683600Y56800D03*
X676000D03*
X668100D03*
X680400Y310500D03*
X703740Y41000D03*
X707000Y32000D03*
X694425Y29500D03*
X693000Y56600D03*
X706000Y61975D03*
X703740Y54118D03*
X703981Y518000D03*
Y498000D03*
X692381Y518000D03*
Y498000D03*
X740381Y518000D03*
Y498000D03*
X761560Y38500D03*
Y30000D03*
Y55500D03*
Y47000D03*
Y64000D03*
X753500Y326000D03*
X753020Y338500D03*
X754000Y356957D03*
X753550Y344161D03*
X759000Y365500D03*
X775425Y364500D03*
X753000Y366500D03*
X766240Y366446D03*
X751981Y498000D03*
Y518000D03*
X784855Y265184D03*
X790000Y259612D03*
X794900Y265979D03*
X798500Y272600D03*
X806000Y265075D03*
X790730Y351839D03*
X791000Y362000D03*
X791563Y342917D03*
X833500Y281000D03*
X815500Y281500D03*
X823206Y281207D03*
X811000Y286000D03*
X815000Y318500D03*
X827500D03*
X833500Y337000D03*
X819500Y336500D03*
X842075Y158924D03*
X843000Y167000D03*
X849500Y281500D03*
X841409Y280566D03*
X853000Y303500D03*
X842600Y317600D03*
X860000Y348000D03*
X879038Y271576D03*
X890676Y272620D03*
X871049Y266946D03*
X872500Y301906D03*
X871000Y348000D03*
X869000Y360500D03*
X903939Y272864D03*
X920899Y272824D03*
X913078Y271503D03*
X915143Y288612D03*
X914500Y303911D03*
X905819Y302819D03*
X898500Y285686D03*
X920000Y320135D03*
X910992Y361075D03*
X930086Y272986D03*
X945201Y272656D03*
X937676Y268356D03*
X932500Y305385D03*
X952000Y286500D03*
X945500Y319000D03*
X942546Y357925D03*
X1043500Y111500D03*
X1034500Y145000D03*
X1039500Y134500D03*
X1043936Y145745D03*
X1019040Y157310D03*
X1022168Y161783D03*
X1017909Y151424D03*
X1024340Y139500D03*
X1016614Y190267D03*
X1039016Y189075D03*
Y183027D03*
X1022000Y171200D03*
X1019700Y166600D03*
X1063500Y111500D03*
X1049356Y143900D03*
X1054500Y148500D03*
X1073154Y140800D03*
X1057500Y155877D03*
X1062500Y191500D03*
X1067701Y270442D03*
X1061600Y276242D03*
X1067679Y317942D03*
X1061600Y323742D03*
X1067707Y365442D03*
X1067531Y412942D03*
X1067730Y460352D03*
X1061600Y466242D03*
X1067866Y507629D03*
X1061600Y513742D03*
X1066500Y538000D03*
Y553000D03*
X1092000Y82500D03*
X1095500Y117075D03*
X1085300Y114016D03*
X1082000Y143600D03*
X1094500Y143144D03*
X1102000Y148000D03*
X1098500Y156937D03*
X1095500Y183500D03*
X1096000Y170500D03*
Y165000D03*
X1092000Y338800D03*
X1095575Y358640D03*
X1091100Y386400D03*
X1095575Y406310D03*
X1130125Y135940D03*
X1121238Y144500D03*
X1120524Y138457D03*
X1123500Y187000D03*
X1108000Y172000D03*
X1113368Y171619D03*
X1113129Y165719D03*
X1114500Y188700D03*
X1131476Y169294D03*
X1133000Y198000D03*
X1117206Y231741D03*
X1117290Y224241D03*
X1106106Y231741D03*
X1114452Y538000D03*
X1123669D03*
X1114452Y553000D03*
X1123669D03*
X1158200Y137700D03*
X1150425Y147401D03*
X1143490Y183560D03*
X1152500Y186500D03*
X1135203Y266860D03*
X1135403Y314360D03*
Y361979D03*
X1135190Y408965D03*
X1135404Y457228D03*
X1135622Y467732D03*
X1188600Y166000D03*
X1177521Y165952D03*
X1165070Y328750D03*
X1193411D03*
X1177836Y349234D03*
X1165190Y471250D03*
X1179500Y476750D03*
Y469750D03*
X1177925Y491734D03*
X1193840Y471250D03*
X1271500Y282000D03*
X1270000Y290000D03*
G54D26*
X178421Y227723D03*
X213017Y300500D03*
Y305000D03*
X221517Y300500D03*
X230517D03*
X221517Y305000D03*
X230517D03*
X387517Y300500D03*
X370017D03*
X378517D03*
X387517Y305000D03*
X378517D03*
X370017D03*
X418536Y433500D03*
X528017Y300500D03*
X537017D03*
Y305500D03*
X528017D03*
X546017Y300500D03*
Y305500D03*
X576017Y433500D03*
X685498Y300500D03*
Y305500D03*
X694498Y300500D03*
X703498D03*
X694498Y305500D03*
X703498D03*
X797517Y330000D03*
Y335000D03*
Y341000D03*
Y346500D03*
Y352000D03*
X834517Y332500D03*
X808517Y341000D03*
Y357000D03*
Y362000D03*
X937517Y306500D03*
X937713Y310885D03*
X938213Y352385D03*
X1042017Y151000D03*
X1046517Y129000D03*
X1057517Y142000D03*
X1046517Y137500D03*
X1100517Y180000D03*
Y183500D03*
X1077360Y359443D03*
X1137812Y143734D03*
X1150517Y154000D03*
G54D35*
X249252Y129685D03*
X529252D03*
X665059Y149408D03*
X980059D03*
X1226024Y174429D03*
Y399429D03*
G54D17*
X82795Y99724D03*
Y482205D03*
G54D62*
X1144019Y149734D03*
X1134571D03*
G54D44*
X418582Y448000D03*
X426456Y444260D03*
Y451740D03*
X576063Y448000D03*
X583937Y444260D03*
Y451740D03*
X890063Y298740D03*
Y291260D03*
X897937Y295000D03*
X908937Y345500D03*
X901063Y349240D03*
Y341760D03*
X1106063Y154500D03*
X1113937Y150760D03*
Y158240D03*
X1144563Y138000D03*
X1152437Y134260D03*
Y141740D03*
G54D53*
X1011000Y98000D03*
X1151000Y90400D03*
G54D45*
X563000Y453240D03*
Y445760D03*
X1110500Y117260D03*
Y124740D03*
X1148000Y206260D03*
Y213740D03*
X1140500Y206260D03*
Y213740D03*
X1155500Y206260D03*
Y213740D03*
X1167600Y189560D03*
Y197040D03*
G54D27*
X178819Y277204D03*
X193819D03*
X253819D03*
X268819D03*
X336299D03*
X351299D03*
X411299D03*
X426299D03*
X493780D03*
X508780D03*
X568780D03*
X583780D03*
X651261D03*
X666261D03*
X726261D03*
X741261D03*
G54D18*
X147234Y239563D03*
Y232563D03*
X1063500Y124500D03*
Y117500D03*
G54D36*
X223819Y447516D03*
X361000Y300516D03*
X381299Y447516D03*
X397047Y300516D03*
X409000D03*
X538780Y447516D03*
X554528Y300516D03*
X549500Y447516D03*
X712009Y300516D03*
X696261Y447516D03*
X826000Y263016D03*
X831000D03*
X811000Y273016D03*
X811500Y323516D03*
X815500D03*
X823500D03*
X827000Y355016D03*
X832500D03*
X856000Y263016D03*
X846000D03*
X851000D03*
X841000D03*
X836000D03*
X852000Y331016D03*
X847500Y357016D03*
X853000D03*
X874000Y353016D03*
X883000D03*
X919500Y278016D03*
X904500Y294516D03*
X908000Y322516D03*
X924500Y358016D03*
X933000Y278016D03*
X926000D03*
X947000Y297016D03*
X940000D03*
X933196Y312401D03*
Y347901D03*
X1067500Y156516D03*
X1077500Y114016D03*
X1076800Y407016D03*
X1080300D03*
X1114000Y142016D03*
X1104500Y140016D03*
X1146760Y168336D03*
G54D63*
X1183561Y130467D03*
Y156451D03*
G54D54*
X1011000Y118000D03*
Y108000D03*
X1161000Y90400D03*
X1171000D03*
G54D64*
X1226024Y174429D03*
Y399429D03*
G54D19*
X152016Y331000D03*
Y335500D03*
Y350500D03*
Y346500D03*
X178390Y223523D03*
X213016Y309500D03*
X221516D03*
X230516D03*
X387516D03*
X370016D03*
X378516D03*
X424035Y457500D03*
X537016Y310500D03*
X528016D03*
X546016D03*
X575516Y457500D03*
X685497Y310500D03*
X694497D03*
X703497D03*
X745016Y338500D03*
Y334500D03*
Y324500D03*
Y328500D03*
X732016Y338500D03*
Y328500D03*
X745016Y342500D03*
Y347700D03*
Y353200D03*
Y361500D03*
X775516Y369500D03*
X797516Y357000D03*
Y362000D03*
X824016Y334000D03*
X834516Y323500D03*
Y328000D03*
X937712Y315385D03*
X938212Y347885D03*
X1034516Y139500D03*
X1046516Y125500D03*
X1060016Y130500D03*
X1070516Y114000D03*
X1060016Y134000D03*
X1046516Y133600D03*
X1088016Y167500D03*
Y174500D03*
X1100516Y165000D03*
Y168500D03*
X1088016Y164000D03*
Y171000D03*
X1077359Y363443D03*
X1137516Y196500D03*
Y200500D03*
G54D37*
X223819Y450483D03*
X361000Y303483D03*
X381299Y450483D03*
X397047Y303483D03*
X409000D03*
X538780Y450483D03*
X554528Y303483D03*
X549500Y450483D03*
X712009Y303483D03*
X696261Y450483D03*
X826000Y265983D03*
X831000D03*
X811000Y275983D03*
X811500Y326483D03*
X815500D03*
X823500D03*
X827000Y357983D03*
X832500D03*
X856000Y265983D03*
X846000D03*
X851000D03*
X841000D03*
X836000D03*
X852000Y333983D03*
X847500Y359983D03*
X853000D03*
X874000Y355983D03*
X883000D03*
X904500Y297483D03*
X919500Y280983D03*
X908000Y325483D03*
X924500Y360983D03*
X947000Y299983D03*
X940000D03*
X933000Y280983D03*
X926000D03*
X933196Y315368D03*
Y350868D03*
X1067500Y159483D03*
X1077500Y116983D03*
X1076800Y409983D03*
X1080300D03*
X1114000Y144983D03*
X1104500Y142983D03*
X1146760Y171303D03*
G54D28*
X165539Y539000D03*
X213539D03*
X261539D03*
X323019D03*
X371019D03*
X419019D03*
X480500D03*
X528500D03*
X576500D03*
X637981D03*
X685981D03*
X733981D03*
G54D46*
X753314Y607542D03*
X766498Y602542D03*
X753420Y635687D03*
X766604Y630687D03*
X766498Y612542D03*
X766604Y640687D03*
X1096017Y607542D03*
X1082833Y602542D03*
Y612542D03*
X1096017Y635687D03*
X1082833Y630687D03*
Y640687D03*
G54D55*
X1046126Y100500D03*
X1061874D03*
X1100126Y107000D03*
X1115874D03*
G54D65*
G01X0Y19685D02*
G03X19685Y0I19685J0D01*
G01X0Y63268D02*
Y19685D01*
G01X11811Y75079D02*
G03X0Y63268I0J-11811D01*
G01Y136102D02*
G03X11811Y124291I11811J0D01*
G01X0Y445787D02*
Y136102D01*
G01X11811Y457598D02*
G03X0Y445787I0J-11811D01*
G01Y518622D02*
G03X11811Y506811I11811J0D01*
G01X0Y559055D02*
Y518622D01*
G01X19685Y578740D02*
G03X0Y559055I0J-19685D01*
G01X19685Y0D02*
X1271654D01*
G01X37795Y75079D02*
X11811D01*
G01Y124291D02*
X37795D01*
G01Y457598D02*
X11811D01*
G01Y506811D02*
X37795D01*
G01X1271654Y578740D02*
X19685D01*
G01X39764Y122323D02*
Y77047D01*
G01D02*
G02X37795Y75079I-1969J1D01*
G01Y124291D02*
G02X39764Y122323I0J-1969D01*
G01Y504843D02*
Y459567D01*
G01D02*
G02X37795Y457598I-1969J0D01*
G01Y506811D02*
G02X39764Y504843I0J-1968D01*
G01X1271654Y0D02*
G03X1291339Y19685I0J19685D01*
G01Y559055D02*
G03X1271654Y578740I-19685J0D01*
G01X1291339Y19685D02*
Y559055D01*
G54D56*
X1049760Y111500D03*
X1057240D03*
X1091240Y135000D03*
X1083760D03*
X1120260Y214500D03*
X1127740D03*
X1146760Y177000D03*
X1154240D03*
G54D47*
X819925Y288000D03*
X822484D03*
X825043D03*
X827602D03*
X830161D03*
X832720D03*
X835280D03*
Y311000D03*
X832720D03*
X830161D03*
X827602D03*
X825043D03*
X822484D03*
X819925D03*
X837839Y288000D03*
X840398D03*
X842957D03*
X845516D03*
X848075D03*
Y311000D03*
X845516D03*
X842957D03*
X840398D03*
X837839D03*
G54D29*
X185224Y539000D03*
X233224D03*
X281224D03*
X342704D03*
X390704D03*
X438704D03*
X500185D03*
X548185D03*
X596185D03*
X657666D03*
X705666D03*
X753666D03*
G54D38*
X268000Y220315D03*
X312500D03*
X357000D03*
X428500D03*
X472500D03*
X516500D03*
X578500D03*
X622500D03*
X666500D03*
X735981D03*
X779981D03*
X823981D03*
G54D66*
G01X-297025Y-1013390D02*
Y1828909D01*
X3691357D01*
Y-1013390D01*
X-297025D01*
G01X4093Y-769672D02*
Y-844672D01*
X504093D01*
Y-769672D01*
X4093D01*
G01X16093Y-834672D02*
Y-839672D01*
G01X14636Y-834672D02*
X17550D01*
G01X22460Y-839672D02*
X19926D01*
Y-834672D01*
X22460D01*
G01X21446Y-837089D02*
X19926D01*
G01X25026Y-834672D02*
Y-839672D01*
X27560D01*
G01X31393Y-839839D02*
X31266Y-839755D01*
Y-839589D01*
X31393Y-839505D01*
X31520Y-839589D01*
Y-839755D01*
X31393Y-839839D01*
G01Y-837589D02*
X31266Y-837505D01*
Y-837339D01*
X31393Y-837255D01*
X31520Y-837339D01*
Y-837505D01*
X31393Y-837589D01*
G01X36176Y-841339D02*
X35543Y-840505D01*
X35226Y-839672D01*
Y-836339D01*
X35543Y-835505D01*
X36176Y-834672D01*
G01X41593D02*
X41086Y-834839D01*
X40706Y-835255D01*
X40453Y-835755D01*
X40263Y-836422D01*
X40200Y-837172D01*
X40263Y-837922D01*
X40453Y-838589D01*
X40706Y-839089D01*
X41086Y-839505D01*
X41593Y-839672D01*
X42100Y-839505D01*
X42480Y-839089D01*
X42733Y-838589D01*
X42923Y-837922D01*
X42986Y-837172D01*
X42923Y-836422D01*
X42733Y-835755D01*
X42480Y-835255D01*
X42100Y-834839D01*
X41593Y-834672D01*
G01X45300Y-838672D02*
X45680Y-839255D01*
X46186Y-839589D01*
X46756Y-839672D01*
X47263Y-839589D01*
X47770Y-839172D01*
X48086Y-838672D01*
X48150Y-838172D01*
X48023Y-837589D01*
X47580Y-837172D01*
X47136Y-837005D01*
X46566D01*
G01X47136D02*
X47516Y-836755D01*
X47833Y-836339D01*
X47960Y-835839D01*
X47833Y-835339D01*
X47516Y-834922D01*
X46946Y-834672D01*
X46376Y-834755D01*
X45806Y-835089D01*
G01X52110Y-841339D02*
X52743Y-840505D01*
X53060Y-839672D01*
Y-836339D01*
X52743Y-835505D01*
X52110Y-834672D01*
G01X55500Y-838672D02*
X55880Y-839255D01*
X56386Y-839589D01*
X56956Y-839672D01*
X57463Y-839589D01*
X57970Y-839172D01*
X58286Y-838672D01*
X58350Y-838172D01*
X58223Y-837589D01*
X57780Y-837172D01*
X57336Y-837005D01*
X56766D01*
G01X57336D02*
X57716Y-836755D01*
X58033Y-836339D01*
X58160Y-835839D01*
X58033Y-835339D01*
X57716Y-834922D01*
X57146Y-834672D01*
X56576Y-834755D01*
X56006Y-835089D01*
G01X60790Y-835505D02*
X61170Y-835005D01*
X61613Y-834755D01*
X62120Y-834672D01*
X62753Y-834839D01*
X63196Y-835255D01*
X63323Y-835755D01*
X63260Y-836255D01*
X63006Y-836672D01*
X61740Y-837505D01*
X61170Y-838089D01*
X60790Y-838922D01*
X60663Y-839672D01*
X63323D01*
G01X66966D02*
X67093Y-838589D01*
X67283Y-837672D01*
X67536Y-836839D01*
X67853Y-835922D01*
X68360Y-834672D01*
X65826D01*
G01X71370Y-838005D02*
X73016D01*
G01X76090Y-835505D02*
X76470Y-835005D01*
X76913Y-834755D01*
X77420Y-834672D01*
X78053Y-834839D01*
X78496Y-835255D01*
X78623Y-835755D01*
X78560Y-836255D01*
X78306Y-836672D01*
X77040Y-837505D01*
X76470Y-838089D01*
X76090Y-838922D01*
X75963Y-839672D01*
X78623D01*
G01X81000Y-838672D02*
X81380Y-839255D01*
X81886Y-839589D01*
X82456Y-839672D01*
X82963Y-839589D01*
X83470Y-839172D01*
X83786Y-838672D01*
X83850Y-838172D01*
X83723Y-837589D01*
X83280Y-837172D01*
X82836Y-837005D01*
X82266D01*
G01X82836D02*
X83216Y-836755D01*
X83533Y-836339D01*
X83660Y-835839D01*
X83533Y-835339D01*
X83216Y-834922D01*
X82646Y-834672D01*
X82076Y-834755D01*
X81506Y-835089D01*
G01X88253Y-839672D02*
Y-834672D01*
X85910Y-838255D01*
X89076D01*
G01X91200Y-838922D02*
X91580Y-839339D01*
X92023Y-839589D01*
X92593Y-839672D01*
X93163Y-839505D01*
X93606Y-839172D01*
X93923Y-838589D01*
X93986Y-837922D01*
X93860Y-837255D01*
X93543Y-836839D01*
X93100Y-836505D01*
X92656Y-836422D01*
X92213Y-836505D01*
X91643Y-836839D01*
X91833Y-834672D01*
X93543D01*
G01X101590Y-839672D02*
Y-834672D01*
X103996D01*
G01X103110Y-837089D02*
X101590D01*
G01X106310Y-839672D02*
X107893Y-834672D01*
X109476Y-839672D01*
G01X108906Y-837922D02*
X106880D01*
G01X111663Y-839672D02*
X114323Y-834672D01*
G01X111663D02*
X114323Y-839672D01*
G01X118093Y-839839D02*
X117966Y-839755D01*
Y-839589D01*
X118093Y-839505D01*
X118220Y-839589D01*
Y-839755D01*
X118093Y-839839D01*
G01Y-837589D02*
X117966Y-837505D01*
Y-837339D01*
X118093Y-837255D01*
X118220Y-837339D01*
Y-837505D01*
X118093Y-837589D01*
G01X122876Y-841339D02*
X122243Y-840505D01*
X121926Y-839672D01*
Y-836339D01*
X122243Y-835505D01*
X122876Y-834672D01*
G01X128293D02*
X127786Y-834839D01*
X127406Y-835255D01*
X127153Y-835755D01*
X126963Y-836422D01*
X126900Y-837172D01*
X126963Y-837922D01*
X127153Y-838589D01*
X127406Y-839089D01*
X127786Y-839505D01*
X128293Y-839672D01*
X128800Y-839505D01*
X129180Y-839089D01*
X129433Y-838589D01*
X129623Y-837922D01*
X129686Y-837172D01*
X129623Y-836422D01*
X129433Y-835755D01*
X129180Y-835255D01*
X128800Y-834839D01*
X128293Y-834672D01*
G01X132000Y-838672D02*
X132380Y-839255D01*
X132886Y-839589D01*
X133456Y-839672D01*
X133963Y-839589D01*
X134470Y-839172D01*
X134786Y-838672D01*
X134850Y-838172D01*
X134723Y-837589D01*
X134280Y-837172D01*
X133836Y-837005D01*
X133266D01*
G01X133836D02*
X134216Y-836755D01*
X134533Y-836339D01*
X134660Y-835839D01*
X134533Y-835339D01*
X134216Y-834922D01*
X133646Y-834672D01*
X133076Y-834755D01*
X132506Y-835089D01*
G01X138810Y-841339D02*
X139443Y-840505D01*
X139760Y-839672D01*
Y-836339D01*
X139443Y-835505D01*
X138810Y-834672D01*
G01X142200Y-838672D02*
X142580Y-839255D01*
X143086Y-839589D01*
X143656Y-839672D01*
X144163Y-839589D01*
X144670Y-839172D01*
X144986Y-838672D01*
X145050Y-838172D01*
X144923Y-837589D01*
X144480Y-837172D01*
X144036Y-837005D01*
X143466D01*
G01X144036D02*
X144416Y-836755D01*
X144733Y-836339D01*
X144860Y-835839D01*
X144733Y-835339D01*
X144416Y-834922D01*
X143846Y-834672D01*
X143276Y-834755D01*
X142706Y-835089D01*
G01X147616Y-839089D02*
X148060Y-839505D01*
X148566Y-839672D01*
X149073Y-839505D01*
X149516Y-839005D01*
X149833Y-838255D01*
X149960Y-837505D01*
Y-836589D01*
X149833Y-835839D01*
X149516Y-835172D01*
X149136Y-834839D01*
X148693Y-834672D01*
X148186Y-834839D01*
X147806Y-835172D01*
X147553Y-835672D01*
X147426Y-836339D01*
X147553Y-836922D01*
X147870Y-837505D01*
X148250Y-837839D01*
X148693Y-837922D01*
X149200Y-837755D01*
X149580Y-837339D01*
X149960Y-836589D01*
G01X153666Y-839672D02*
X153793Y-838589D01*
X153983Y-837672D01*
X154236Y-836839D01*
X154553Y-835922D01*
X155060Y-834672D01*
X152526D01*
G01X158070Y-838005D02*
X159716D01*
G01X162600Y-838672D02*
X162980Y-839255D01*
X163486Y-839589D01*
X164056Y-839672D01*
X164563Y-839589D01*
X165070Y-839172D01*
X165386Y-838672D01*
X165450Y-838172D01*
X165323Y-837589D01*
X164880Y-837172D01*
X164436Y-837005D01*
X163866D01*
G01X164436D02*
X164816Y-836755D01*
X165133Y-836339D01*
X165260Y-835839D01*
X165133Y-835339D01*
X164816Y-834922D01*
X164246Y-834672D01*
X163676Y-834755D01*
X163106Y-835089D01*
G01X167890Y-837589D02*
X168333Y-837005D01*
X168713Y-836672D01*
X169220Y-836505D01*
X169663Y-836672D01*
X169980Y-837005D01*
X170233Y-837505D01*
X170296Y-838089D01*
X170233Y-838589D01*
X169980Y-839089D01*
X169600Y-839505D01*
X169156Y-839672D01*
X168650Y-839505D01*
X168206Y-839005D01*
X167953Y-838255D01*
X167890Y-837422D01*
X168016Y-836339D01*
X168206Y-835755D01*
X168523Y-835172D01*
X168966Y-834755D01*
X169410Y-834672D01*
X169853Y-834839D01*
X170170Y-835255D01*
G01X174193Y-839672D02*
Y-834672D01*
X173433Y-835672D01*
G01Y-839672D02*
X174953D01*
G01X180053D02*
Y-834672D01*
X177710Y-838255D01*
X180876D01*
G01X199093Y-769672D02*
Y-844672D01*
G01Y-819672D02*
X302093D01*
Y-794672D01*
G01X199093D02*
X302093D01*
G01X309600Y-829672D02*
Y-824672D01*
X310866D01*
X311373Y-824922D01*
X311753Y-825255D01*
X312070Y-825755D01*
X312323Y-826339D01*
X312386Y-827172D01*
X312323Y-828005D01*
X312070Y-828589D01*
X311753Y-829089D01*
X311373Y-829422D01*
X310866Y-829672D01*
X309600D01*
G01X314510D02*
X316093Y-824672D01*
X317676Y-829672D01*
G01X317106Y-827922D02*
X315080D01*
G01X321193Y-824672D02*
Y-829672D01*
G01X319736Y-824672D02*
X322650D01*
G01X327560Y-829672D02*
X325026D01*
Y-824672D01*
X327560D01*
G01X326546Y-827089D02*
X325026D01*
G01X331393Y-829839D02*
X331266Y-829755D01*
Y-829589D01*
X331393Y-829505D01*
X331520Y-829589D01*
Y-829755D01*
X331393Y-829839D01*
G01Y-827589D02*
X331266Y-827505D01*
Y-827339D01*
X331393Y-827255D01*
X331520Y-827339D01*
Y-827505D01*
X331393Y-827589D01*
G01X304093Y-769672D02*
Y-844672D01*
G01X302093Y-769672D02*
Y-844672D01*
G01X304093Y-819672D02*
X504093D01*
G01X309726Y-804672D02*
Y-799672D01*
X311246D01*
X311753Y-799922D01*
X312133Y-800505D01*
X312260Y-801172D01*
X312133Y-801839D01*
X311816Y-802339D01*
X311246Y-802589D01*
X309726D01*
G01X314953Y-804839D02*
X317233Y-799672D01*
G01X319736Y-804672D02*
Y-799672D01*
X322650Y-804672D01*
Y-799672D01*
G01X326293Y-804839D02*
X326166Y-804755D01*
Y-804589D01*
X326293Y-804505D01*
X326420Y-804589D01*
Y-804755D01*
X326293Y-804839D01*
G01Y-802589D02*
X326166Y-802505D01*
Y-802339D01*
X326293Y-802255D01*
X326420Y-802339D01*
Y-802505D01*
X326293Y-802589D01*
G01X304093Y-794672D02*
X504093D01*
G01X309726Y-779672D02*
Y-774672D01*
X311246D01*
X311753Y-774922D01*
X312133Y-775505D01*
X312260Y-776172D01*
X312133Y-776839D01*
X311816Y-777339D01*
X311246Y-777589D01*
X309726D01*
G01X314826Y-779672D02*
Y-774672D01*
X316410D01*
X316916Y-774922D01*
X317233Y-775255D01*
X317360Y-775922D01*
X317233Y-776589D01*
X316853Y-777005D01*
X316410Y-777255D01*
X314826D01*
G01X316410D02*
X317360Y-779672D01*
G01X321193D02*
X320686Y-779589D01*
X320243Y-779255D01*
X319863Y-778755D01*
X319610Y-778172D01*
X319483Y-777505D01*
Y-776839D01*
X319610Y-776172D01*
X319863Y-775589D01*
X320243Y-775089D01*
X320686Y-774755D01*
X321193Y-774672D01*
X321700Y-774755D01*
X322143Y-775089D01*
X322523Y-775589D01*
X322776Y-776172D01*
X322903Y-776839D01*
Y-777505D01*
X322776Y-778172D01*
X322523Y-778755D01*
X322143Y-779255D01*
X321700Y-779589D01*
X321193Y-779672D01*
G01X325026Y-778672D02*
X325343Y-779172D01*
X325723Y-779505D01*
X326166Y-779672D01*
X326673Y-779505D01*
X327053Y-779172D01*
X327433Y-778672D01*
X327560Y-778005D01*
Y-774672D01*
G01X332660Y-779672D02*
X330126D01*
Y-774672D01*
X332660D01*
G01X331646Y-777089D02*
X330126D01*
G01X337886Y-775089D02*
X337506Y-774839D01*
X337063Y-774672D01*
X336556D01*
X335986Y-774922D01*
X335543Y-775339D01*
X335226Y-775839D01*
X334973Y-776672D01*
X334910Y-777422D01*
X335036Y-778172D01*
X335226Y-778672D01*
X335606Y-779172D01*
X336050Y-779505D01*
X336493Y-779672D01*
X336936D01*
X337380Y-779505D01*
X337760Y-779255D01*
X338076Y-778922D01*
G01X341593Y-774672D02*
Y-779672D01*
G01X340136Y-774672D02*
X343050D01*
G01X346693Y-779839D02*
X346566Y-779755D01*
Y-779589D01*
X346693Y-779505D01*
X346820Y-779589D01*
Y-779755D01*
X346693Y-779839D01*
G01Y-777589D02*
X346566Y-777505D01*
Y-777339D01*
X346693Y-777255D01*
X346820Y-777339D01*
Y-777505D01*
X346693Y-777589D01*
G01X419093Y-819672D02*
Y-844672D01*
G01X421726Y-822172D02*
Y-827172D01*
X424260D01*
G01X427333Y-822172D02*
X428853D01*
G01X428093D02*
Y-827172D01*
G01X427333D02*
X428853D01*
G01X433700Y-824505D02*
X433953Y-824255D01*
X434143Y-823839D01*
X434270Y-823255D01*
X434143Y-822755D01*
X433890Y-822422D01*
X433446Y-822172D01*
X431736D01*
Y-827172D01*
X433826D01*
X434270Y-826839D01*
X434523Y-826339D01*
X434650Y-825755D01*
X434523Y-825172D01*
X434143Y-824672D01*
X433700Y-824505D01*
X431736D01*
G01X438293Y-827339D02*
X438166Y-827255D01*
Y-827089D01*
X438293Y-827005D01*
X438420Y-827089D01*
Y-827255D01*
X438293Y-827339D01*
G01Y-825089D02*
X438166Y-825005D01*
Y-824839D01*
X438293Y-824755D01*
X438420Y-824839D01*
Y-825005D01*
X438293Y-825089D01*
G01X470106Y-847839D02*
X470213Y-847714D01*
X470293Y-847505D01*
X470346Y-847214D01*
X470293Y-846964D01*
X470186Y-846797D01*
X470000Y-846672D01*
X469280D01*
Y-849172D01*
X470160D01*
X470346Y-849005D01*
X470453Y-848755D01*
X470506Y-848464D01*
X470453Y-848172D01*
X470293Y-847922D01*
X470106Y-847839D01*
X469280D01*
G01X472573Y-849172D02*
Y-847505D01*
G01Y-847797D02*
X472466Y-847630D01*
X472306Y-847547D01*
X472120Y-847505D01*
X471933Y-847589D01*
X471773Y-847755D01*
X471666Y-848005D01*
X471613Y-848339D01*
X471666Y-848672D01*
X471773Y-848922D01*
X471933Y-849089D01*
X472120Y-849172D01*
X472306Y-849130D01*
X472466Y-849005D01*
X472573Y-848839D01*
G01X473893Y-848880D02*
X474026Y-849047D01*
X474213Y-849172D01*
X474373D01*
X474533Y-849089D01*
X474640Y-848964D01*
X474693Y-848797D01*
X474666Y-848547D01*
X474560Y-848422D01*
X474080Y-848172D01*
X473973Y-847880D01*
X474026Y-847672D01*
X474133Y-847547D01*
X474293Y-847505D01*
X474453Y-847547D01*
X474613Y-847672D01*
G01X476093Y-848047D02*
X476946D01*
X476866Y-847755D01*
X476733Y-847589D01*
X476546Y-847505D01*
X476360Y-847547D01*
X476200Y-847672D01*
X476093Y-847964D01*
X476040Y-848214D01*
Y-848464D01*
X476093Y-848714D01*
X476226Y-848964D01*
X476386Y-849130D01*
X476573Y-849172D01*
X476760Y-849089D01*
X476946Y-848839D01*
G01X478213Y-849172D02*
Y-846672D01*
G01Y-847922D02*
X478346Y-847672D01*
X478506Y-847547D01*
X478666Y-847505D01*
X478906Y-847589D01*
X479066Y-847755D01*
X479173Y-848047D01*
Y-848380D01*
X479120Y-848714D01*
X479013Y-848964D01*
X478826Y-849130D01*
X478666Y-849172D01*
X478506Y-849130D01*
X478346Y-849005D01*
X478213Y-848797D01*
G01X480893Y-849172D02*
X480733Y-849130D01*
X480573Y-848964D01*
X480466Y-848672D01*
X480413Y-848339D01*
X480466Y-848005D01*
X480573Y-847714D01*
X480733Y-847547D01*
X480893Y-847505D01*
X481053Y-847547D01*
X481213Y-847714D01*
X481320Y-848005D01*
X481346Y-848339D01*
X481320Y-848672D01*
X481213Y-848964D01*
X481053Y-849130D01*
X480893Y-849172D01*
G01X483573D02*
Y-847505D01*
G01Y-847797D02*
X483466Y-847630D01*
X483306Y-847547D01*
X483120Y-847505D01*
X482933Y-847589D01*
X482773Y-847755D01*
X482666Y-848005D01*
X482613Y-848339D01*
X482666Y-848672D01*
X482773Y-848922D01*
X482933Y-849089D01*
X483120Y-849172D01*
X483306Y-849130D01*
X483466Y-849005D01*
X483573Y-848839D01*
G01X484920Y-849172D02*
Y-847505D01*
G01Y-847839D02*
X485053Y-847672D01*
X485186Y-847547D01*
X485373Y-847505D01*
X485506Y-847547D01*
X485666Y-847672D01*
G01X487973Y-846672D02*
Y-849172D01*
G01Y-848797D02*
X487866Y-849005D01*
X487706Y-849130D01*
X487520Y-849172D01*
X487306Y-849089D01*
X487146Y-848880D01*
X487040Y-848630D01*
X487013Y-848339D01*
X487040Y-848047D01*
X487146Y-847797D01*
X487306Y-847589D01*
X487520Y-847505D01*
X487706Y-847547D01*
X487840Y-847630D01*
X487973Y-847797D01*
G01X491360Y-849172D02*
Y-846672D01*
X492026D01*
X492240Y-846797D01*
X492373Y-846964D01*
X492426Y-847297D01*
X492373Y-847630D01*
X492213Y-847839D01*
X492026Y-847964D01*
X491360D01*
G01X492026D02*
X492426Y-849172D01*
G01X493693Y-848047D02*
X494546D01*
X494466Y-847755D01*
X494333Y-847589D01*
X494146Y-847505D01*
X493960Y-847547D01*
X493800Y-847672D01*
X493693Y-847964D01*
X493640Y-848214D01*
Y-848464D01*
X493693Y-848714D01*
X493826Y-848964D01*
X493986Y-849130D01*
X494173Y-849172D01*
X494360Y-849089D01*
X494546Y-848839D01*
G01X495813Y-847505D02*
X496293Y-849172D01*
X496773Y-847505D01*
G01X498493Y-849255D02*
X498440Y-849214D01*
Y-849130D01*
X498493Y-849089D01*
X498546Y-849130D01*
Y-849214D01*
X498493Y-849255D01*
G01X500693Y-849172D02*
X500880Y-849130D01*
X501093Y-849005D01*
X501226Y-848797D01*
X501280Y-848505D01*
X501226Y-848214D01*
X501066Y-847964D01*
X500826Y-847839D01*
X500560D01*
X500400Y-847755D01*
X500266Y-847547D01*
X500213Y-847255D01*
X500293Y-846964D01*
X500480Y-846755D01*
X500693Y-846672D01*
X500906Y-846755D01*
X501093Y-846964D01*
X501173Y-847255D01*
X501120Y-847547D01*
X500986Y-847755D01*
X500826Y-847839D01*
X500560D01*
X500320Y-847964D01*
X500160Y-848214D01*
X500106Y-848505D01*
X500160Y-848797D01*
X500293Y-849005D01*
X500506Y-849130D01*
X500693Y-849172D01*
G01X503106Y-847839D02*
X503213Y-847714D01*
X503293Y-847505D01*
X503346Y-847214D01*
X503293Y-846964D01*
X503186Y-846797D01*
X503000Y-846672D01*
X502280D01*
Y-849172D01*
X503160D01*
X503346Y-849005D01*
X503453Y-848755D01*
X503506Y-848464D01*
X503453Y-848172D01*
X503293Y-847922D01*
X503106Y-847839D01*
X502280D01*
G01X465993Y-822172D02*
Y-827172D01*
G01X464536Y-822172D02*
X467450D01*
G01X471093Y-827172D02*
X470713Y-827089D01*
X470333Y-826755D01*
X470080Y-826172D01*
X469953Y-825505D01*
X470080Y-824839D01*
X470333Y-824255D01*
X470713Y-823922D01*
X471093Y-823839D01*
X471473Y-823922D01*
X471853Y-824255D01*
X472106Y-824839D01*
X472170Y-825505D01*
X472106Y-826172D01*
X471853Y-826755D01*
X471473Y-827089D01*
X471093Y-827172D01*
G01X476193D02*
X475813Y-827089D01*
X475433Y-826755D01*
X475180Y-826172D01*
X475053Y-825505D01*
X475180Y-824839D01*
X475433Y-824255D01*
X475813Y-823922D01*
X476193Y-823839D01*
X476573Y-823922D01*
X476953Y-824255D01*
X477206Y-824839D01*
X477270Y-825505D01*
X477206Y-826172D01*
X476953Y-826755D01*
X476573Y-827089D01*
X476193Y-827172D01*
G01X481293D02*
Y-822172D01*
G01X486393Y-827339D02*
X486266Y-827255D01*
Y-827089D01*
X486393Y-827005D01*
X486520Y-827089D01*
Y-827255D01*
X486393Y-827339D01*
G01Y-825089D02*
X486266Y-825005D01*
Y-824839D01*
X486393Y-824755D01*
X486520Y-824839D01*
Y-825005D01*
X486393Y-825089D01*
G01X462093Y-819672D02*
Y-844672D01*
G01Y-794672D02*
Y-819672D01*
G01X464726Y-802172D02*
Y-797172D01*
X466310D01*
X466816Y-797422D01*
X467133Y-797755D01*
X467260Y-798422D01*
X467133Y-799089D01*
X466753Y-799505D01*
X466310Y-799755D01*
X464726D01*
G01X466310D02*
X467260Y-802172D01*
G01X472360D02*
X469826D01*
Y-797172D01*
X472360D01*
G01X471346Y-799589D02*
X469826D01*
G01X474610Y-797172D02*
X476193Y-802172D01*
X477776Y-797172D01*
G01X481293Y-802339D02*
X481166Y-802255D01*
Y-802089D01*
X481293Y-802005D01*
X481420Y-802089D01*
Y-802255D01*
X481293Y-802339D01*
G01Y-800089D02*
X481166Y-800005D01*
Y-799839D01*
X481293Y-799755D01*
X481420Y-799839D01*
Y-800005D01*
X481293Y-800089D01*
G01X-297025Y-1013390D02*
Y1828909D01*
X3691357D01*
Y-1013390D01*
X-297025D01*
G01X16913Y-817022D02*
X18480D01*
Y-818912D01*
X18010Y-819542D01*
X17461Y-819962D01*
X16678Y-820172D01*
X15895Y-819962D01*
X15346Y-819542D01*
X14876Y-818912D01*
X14563Y-818177D01*
X14406Y-817337D01*
Y-816602D01*
X14563Y-815972D01*
X14876Y-815237D01*
X15346Y-814607D01*
X15816Y-814187D01*
X16443Y-813872D01*
X16991D01*
X17618Y-814082D01*
X18088Y-814502D01*
G01X21020Y-813872D02*
Y-818387D01*
X21333Y-819332D01*
X21960Y-819962D01*
X22743Y-820172D01*
X23526Y-819962D01*
X24153Y-819332D01*
X24466Y-818387D01*
Y-813872D01*
G01X28103D02*
X29983D01*
G01X29043D02*
Y-820172D01*
G01X28103D02*
X29983D01*
G01X33698Y-819332D02*
X34325Y-819857D01*
X35030Y-820172D01*
X35656D01*
X36283Y-819857D01*
X36753Y-819332D01*
X36988Y-818597D01*
X36831Y-817862D01*
X36440Y-817232D01*
X35735Y-816812D01*
X34795Y-816602D01*
X34246Y-816182D01*
X34011Y-815447D01*
X34168Y-814712D01*
X34560Y-814187D01*
X35108Y-813872D01*
X35656D01*
X36205Y-814082D01*
X36675Y-814607D01*
G01X39998Y-820172D02*
Y-813872D01*
G01X43288D02*
Y-820172D01*
G01Y-817022D02*
X39998D01*
G01X45985Y-820172D02*
X47943Y-813872D01*
X49901Y-820172D01*
G01X49196Y-817967D02*
X46690D01*
G01X52441Y-820172D02*
Y-813872D01*
X56045Y-820172D01*
Y-813872D01*
G01X65120Y-820172D02*
Y-813872D01*
X66686D01*
X67313Y-814187D01*
X67783Y-814607D01*
X68175Y-815237D01*
X68488Y-815972D01*
X68566Y-817022D01*
X68488Y-818072D01*
X68175Y-818807D01*
X67783Y-819437D01*
X67313Y-819857D01*
X66686Y-820172D01*
X65120D01*
G01X72203Y-813872D02*
X74083D01*
G01X73143D02*
Y-820172D01*
G01X72203D02*
X74083D01*
G01X77798Y-819332D02*
X78425Y-819857D01*
X79130Y-820172D01*
X79756D01*
X80383Y-819857D01*
X80853Y-819332D01*
X81088Y-818597D01*
X80931Y-817862D01*
X80540Y-817232D01*
X79835Y-816812D01*
X78895Y-816602D01*
X78346Y-816182D01*
X78111Y-815447D01*
X78268Y-814712D01*
X78660Y-814187D01*
X79208Y-813872D01*
X79756D01*
X80305Y-814082D01*
X80775Y-814607D01*
G01X85743Y-813872D02*
Y-820172D01*
G01X83941Y-813872D02*
X87545D01*
G01X92043Y-820382D02*
X91886Y-820277D01*
Y-820067D01*
X92043Y-819962D01*
X92200Y-820067D01*
Y-820277D01*
X92043Y-820382D01*
G01X98186Y-821327D02*
X98500Y-819962D01*
G01X104643Y-813872D02*
Y-820172D01*
G01X102841Y-813872D02*
X106445D01*
G01X108985Y-820172D02*
X110943Y-813872D01*
X112901Y-820172D01*
G01X112196Y-817967D02*
X109690D01*
G01X117243Y-820172D02*
X116616Y-820067D01*
X116068Y-819647D01*
X115598Y-819017D01*
X115285Y-818282D01*
X115128Y-817442D01*
Y-816602D01*
X115285Y-815762D01*
X115598Y-815027D01*
X116068Y-814397D01*
X116616Y-813977D01*
X117243Y-813872D01*
X117870Y-813977D01*
X118418Y-814397D01*
X118888Y-815027D01*
X119201Y-815762D01*
X119358Y-816602D01*
Y-817442D01*
X119201Y-818282D01*
X118888Y-819017D01*
X118418Y-819647D01*
X117870Y-820067D01*
X117243Y-820172D01*
G01X123543D02*
Y-817337D01*
X121976Y-813872D01*
G01X125110D02*
X123543Y-817337D01*
G01X128120Y-813872D02*
Y-818387D01*
X128433Y-819332D01*
X129060Y-819962D01*
X129843Y-820172D01*
X130626Y-819962D01*
X131253Y-819332D01*
X131566Y-818387D01*
Y-813872D01*
G01X134185Y-820172D02*
X136143Y-813872D01*
X138101Y-820172D01*
G01X137396Y-817967D02*
X134890D01*
G01X140641Y-820172D02*
Y-813872D01*
X144245Y-820172D01*
Y-813872D01*
G01X18166Y-824397D02*
X17696Y-824082D01*
X17148Y-823872D01*
X16521D01*
X15816Y-824187D01*
X15268Y-824712D01*
X14876Y-825342D01*
X14563Y-826392D01*
X14485Y-827337D01*
X14641Y-828282D01*
X14876Y-828912D01*
X15346Y-829542D01*
X15895Y-829962D01*
X16443Y-830172D01*
X16991D01*
X17540Y-829962D01*
X18010Y-829647D01*
X18401Y-829227D01*
G01X21803Y-823872D02*
X23683D01*
G01X22743D02*
Y-830172D01*
G01X21803D02*
X23683D01*
G01X29043Y-823872D02*
Y-830172D01*
G01X27241Y-823872D02*
X30845D01*
G01X35343Y-830172D02*
Y-827337D01*
X33776Y-823872D01*
G01X36910D02*
X35343Y-827337D01*
G01X46220Y-828912D02*
X46690Y-829647D01*
X47316Y-830067D01*
X48021Y-830172D01*
X48648Y-830067D01*
X49275Y-829542D01*
X49666Y-828912D01*
X49745Y-828282D01*
X49588Y-827547D01*
X49040Y-827022D01*
X48491Y-826812D01*
X47786D01*
G01X48491D02*
X48961Y-826497D01*
X49353Y-825972D01*
X49510Y-825342D01*
X49353Y-824712D01*
X48961Y-824187D01*
X48256Y-823872D01*
X47551Y-823977D01*
X46846Y-824397D01*
G01X52520Y-828912D02*
X52990Y-829647D01*
X53616Y-830067D01*
X54321Y-830172D01*
X54948Y-830067D01*
X55575Y-829542D01*
X55966Y-828912D01*
X56045Y-828282D01*
X55888Y-827547D01*
X55340Y-827022D01*
X54791Y-826812D01*
X54086D01*
G01X54791D02*
X55261Y-826497D01*
X55653Y-825972D01*
X55810Y-825342D01*
X55653Y-824712D01*
X55261Y-824187D01*
X54556Y-823872D01*
X53851Y-823977D01*
X53146Y-824397D01*
G01X58820Y-828912D02*
X59290Y-829647D01*
X59916Y-830067D01*
X60621Y-830172D01*
X61248Y-830067D01*
X61875Y-829542D01*
X62266Y-828912D01*
X62345Y-828282D01*
X62188Y-827547D01*
X61640Y-827022D01*
X61091Y-826812D01*
X60386D01*
G01X61091D02*
X61561Y-826497D01*
X61953Y-825972D01*
X62110Y-825342D01*
X61953Y-824712D01*
X61561Y-824187D01*
X60856Y-823872D01*
X60151Y-823977D01*
X59446Y-824397D01*
G01X66686Y-830172D02*
X66843Y-828807D01*
X67078Y-827652D01*
X67391Y-826602D01*
X67783Y-825447D01*
X68410Y-823872D01*
X65276D01*
G01X72986Y-830172D02*
X73143Y-828807D01*
X73378Y-827652D01*
X73691Y-826602D01*
X74083Y-825447D01*
X74710Y-823872D01*
X71576D01*
G01X79286Y-831327D02*
X79600Y-829962D01*
G01X85743Y-823872D02*
Y-830172D01*
G01X83941Y-823872D02*
X87545D01*
G01X90085Y-830172D02*
X92043Y-823872D01*
X94001Y-830172D01*
G01X93296Y-827967D02*
X90790D01*
G01X97403Y-823872D02*
X99283D01*
G01X98343D02*
Y-830172D01*
G01X97403D02*
X99283D01*
G01X102293Y-823872D02*
X103390Y-830172D01*
X104643Y-823872D01*
X105896Y-830172D01*
X106993Y-823872D01*
G01X108985Y-830172D02*
X110943Y-823872D01*
X112901Y-830172D01*
G01X112196Y-827967D02*
X109690D01*
G01X115441Y-830172D02*
Y-823872D01*
X119045Y-830172D01*
Y-823872D01*
G01X129451Y-832272D02*
X128668Y-831222D01*
X128276Y-830172D01*
Y-825972D01*
X128668Y-824922D01*
X129451Y-823872D01*
G01X140876Y-830172D02*
Y-823872D01*
X142835D01*
X143461Y-824187D01*
X143853Y-824607D01*
X144010Y-825447D01*
X143853Y-826287D01*
X143383Y-826812D01*
X142835Y-827127D01*
X140876D01*
G01X142835D02*
X144010Y-830172D01*
G01X148743Y-830382D02*
X148586Y-830277D01*
Y-830067D01*
X148743Y-829962D01*
X148900Y-830067D01*
Y-830277D01*
X148743Y-830382D01*
G01X155043Y-830172D02*
X154416Y-830067D01*
X153868Y-829647D01*
X153398Y-829017D01*
X153085Y-828282D01*
X152928Y-827442D01*
Y-826602D01*
X153085Y-825762D01*
X153398Y-825027D01*
X153868Y-824397D01*
X154416Y-823977D01*
X155043Y-823872D01*
X155670Y-823977D01*
X156218Y-824397D01*
X156688Y-825027D01*
X157001Y-825762D01*
X157158Y-826602D01*
Y-827442D01*
X157001Y-828282D01*
X156688Y-829017D01*
X156218Y-829647D01*
X155670Y-830067D01*
X155043Y-830172D01*
G01X161343Y-830382D02*
X161186Y-830277D01*
Y-830067D01*
X161343Y-829962D01*
X161500Y-830067D01*
Y-830277D01*
X161343Y-830382D01*
G01X169366Y-824397D02*
X168896Y-824082D01*
X168348Y-823872D01*
X167721D01*
X167016Y-824187D01*
X166468Y-824712D01*
X166076Y-825342D01*
X165763Y-826392D01*
X165685Y-827337D01*
X165841Y-828282D01*
X166076Y-828912D01*
X166546Y-829542D01*
X167095Y-829962D01*
X167643Y-830172D01*
X168191D01*
X168740Y-829962D01*
X169210Y-829647D01*
X169601Y-829227D01*
G01X173943Y-830382D02*
X173786Y-830277D01*
Y-830067D01*
X173943Y-829962D01*
X174100Y-830067D01*
Y-830277D01*
X173943Y-830382D01*
G01X180635Y-832272D02*
X181418Y-831222D01*
X181810Y-830172D01*
Y-825972D01*
X181418Y-824922D01*
X180635Y-823872D01*
G01X38743Y-799472D02*
X36223Y-799055D01*
X34018Y-797389D01*
X32128Y-794889D01*
X30868Y-791972D01*
X30238Y-788639D01*
Y-785305D01*
X30868Y-781972D01*
X32128Y-779055D01*
X34018Y-776556D01*
X36223Y-774889D01*
X38743Y-774472D01*
X41263Y-774889D01*
X43468Y-776556D01*
X45358Y-779055D01*
X46618Y-781972D01*
X47248Y-785305D01*
Y-788639D01*
X46618Y-791972D01*
X45358Y-794889D01*
X43468Y-797389D01*
X41263Y-799055D01*
X38743Y-799472D01*
G01X41263Y-792805D02*
X45043Y-799472D01*
G01X58588Y-782806D02*
Y-794472D01*
X59848Y-797389D01*
X61738Y-799055D01*
X63943Y-799472D01*
X66148Y-799055D01*
X68038Y-797389D01*
X69298Y-794472D01*
G01Y-799472D02*
Y-782806D01*
G01X94813Y-799472D02*
Y-782806D01*
G01Y-785722D02*
X93553Y-784056D01*
X91663Y-783222D01*
X89458Y-782806D01*
X87253Y-783639D01*
X85363Y-785305D01*
X84103Y-787806D01*
X83473Y-791139D01*
X84103Y-794472D01*
X85363Y-796973D01*
X87253Y-798639D01*
X89458Y-799472D01*
X91663Y-799055D01*
X93553Y-797806D01*
X94813Y-796139D01*
G01X108988Y-799472D02*
Y-782806D01*
G01Y-786972D02*
X110248Y-784889D01*
X112138Y-783222D01*
X114658Y-782806D01*
X116863Y-783222D01*
X118753Y-784889D01*
X119698Y-787806D01*
Y-799472D01*
G01X139543Y-774472D02*
Y-799472D01*
G01X135133Y-782806D02*
X143953D01*
G01X170413Y-799472D02*
Y-782806D01*
G01Y-785722D02*
X169153Y-784056D01*
X167263Y-783222D01*
X165058Y-782806D01*
X162853Y-783639D01*
X160963Y-785305D01*
X159703Y-787806D01*
X159073Y-791139D01*
X159703Y-794472D01*
X160963Y-796973D01*
X162853Y-798639D01*
X165058Y-799472D01*
X167263Y-799055D01*
X169153Y-797806D01*
X170413Y-796139D01*
G01X14641Y-810172D02*
Y-803872D01*
X18245Y-810172D01*
Y-803872D01*
G01X22743Y-810172D02*
X22116Y-810067D01*
X21568Y-809647D01*
X21098Y-809017D01*
X20785Y-808282D01*
X20628Y-807442D01*
Y-806602D01*
X20785Y-805762D01*
X21098Y-805027D01*
X21568Y-804397D01*
X22116Y-803977D01*
X22743Y-803872D01*
X23370Y-803977D01*
X23918Y-804397D01*
X24388Y-805027D01*
X24701Y-805762D01*
X24858Y-806602D01*
Y-807442D01*
X24701Y-808282D01*
X24388Y-809017D01*
X23918Y-809647D01*
X23370Y-810067D01*
X22743Y-810172D01*
G01X29043Y-810382D02*
X28886Y-810277D01*
Y-810067D01*
X29043Y-809962D01*
X29200Y-810067D01*
Y-810277D01*
X29043Y-810382D01*
G01X33855Y-804922D02*
X34325Y-804292D01*
X34873Y-803977D01*
X35500Y-803872D01*
X36283Y-804082D01*
X36831Y-804607D01*
X36988Y-805237D01*
X36910Y-805867D01*
X36596Y-806392D01*
X35030Y-807442D01*
X34325Y-808177D01*
X33855Y-809227D01*
X33698Y-810172D01*
X36988D01*
G01X41643D02*
Y-803872D01*
X40703Y-805132D01*
G01Y-810172D02*
X42583D01*
G01X47943D02*
Y-803872D01*
X47003Y-805132D01*
G01Y-810172D02*
X48883D01*
G01X54086Y-811327D02*
X54400Y-809962D01*
G01X58193Y-803872D02*
X59290Y-810172D01*
X60543Y-803872D01*
X61796Y-810172D01*
X62893Y-803872D01*
G01X68410Y-810172D02*
X65276D01*
Y-803872D01*
X68410D01*
G01X67156Y-806917D02*
X65276D01*
G01X71341Y-810172D02*
Y-803872D01*
X74945Y-810172D01*
Y-803872D01*
G01X77798Y-810172D02*
Y-803872D01*
G01X81088D02*
Y-810172D01*
G01Y-807022D02*
X77798D01*
G01X84020Y-803872D02*
Y-808387D01*
X84333Y-809332D01*
X84960Y-809962D01*
X85743Y-810172D01*
X86526Y-809962D01*
X87153Y-809332D01*
X87466Y-808387D01*
Y-803872D01*
G01X90085Y-810172D02*
X92043Y-803872D01*
X94001Y-810172D01*
G01X93296Y-807967D02*
X90790D01*
G01X103155Y-804922D02*
X103625Y-804292D01*
X104173Y-803977D01*
X104800Y-803872D01*
X105583Y-804082D01*
X106131Y-804607D01*
X106288Y-805237D01*
X106210Y-805867D01*
X105896Y-806392D01*
X104330Y-807442D01*
X103625Y-808177D01*
X103155Y-809227D01*
X102998Y-810172D01*
X106288D01*
G01X109141D02*
Y-803872D01*
X112745Y-810172D01*
Y-803872D01*
G01X115520Y-810172D02*
Y-803872D01*
X117086D01*
X117713Y-804187D01*
X118183Y-804607D01*
X118575Y-805237D01*
X118888Y-805972D01*
X118966Y-807022D01*
X118888Y-808072D01*
X118575Y-808807D01*
X118183Y-809437D01*
X117713Y-809857D01*
X117086Y-810172D01*
X115520D01*
G01X128276D02*
Y-803872D01*
X130235D01*
X130861Y-804187D01*
X131253Y-804607D01*
X131410Y-805447D01*
X131253Y-806287D01*
X130783Y-806812D01*
X130235Y-807127D01*
X128276D01*
G01X130235D02*
X131410Y-810172D01*
G01X134420D02*
Y-803872D01*
X135986D01*
X136613Y-804187D01*
X137083Y-804607D01*
X137475Y-805237D01*
X137788Y-805972D01*
X137866Y-807022D01*
X137788Y-808072D01*
X137475Y-808807D01*
X137083Y-809437D01*
X136613Y-809857D01*
X135986Y-810172D01*
X134420D01*
G01X142443Y-810382D02*
X142286Y-810277D01*
Y-810067D01*
X142443Y-809962D01*
X142600Y-810067D01*
Y-810277D01*
X142443Y-810382D01*
G01X210093Y-779172D02*
Y-787172D01*
X214093D01*
G01X221893D02*
Y-781839D01*
G01Y-782772D02*
X221493Y-782239D01*
X220893Y-781972D01*
X220193Y-781839D01*
X219493Y-782105D01*
X218893Y-782639D01*
X218493Y-783439D01*
X218293Y-784505D01*
X218493Y-785572D01*
X218893Y-786372D01*
X219493Y-786905D01*
X220193Y-787172D01*
X220893Y-787039D01*
X221493Y-786639D01*
X221893Y-786106D01*
G01X225993Y-789572D02*
X226593Y-789839D01*
X227393Y-789572D01*
X227893Y-789039D01*
X228293Y-788372D01*
X228893Y-786239D01*
X230193Y-781839D01*
G01X226993D02*
X228893Y-786239D01*
G01X234593Y-783572D02*
X237793D01*
X237493Y-782639D01*
X236993Y-782105D01*
X236293Y-781839D01*
X235593Y-781972D01*
X234993Y-782372D01*
X234593Y-783305D01*
X234393Y-784106D01*
Y-784905D01*
X234593Y-785705D01*
X235093Y-786505D01*
X235693Y-787039D01*
X236393Y-787172D01*
X237093Y-786905D01*
X237793Y-786106D01*
G01X242693Y-787172D02*
Y-781839D01*
G01Y-782905D02*
X243193Y-782372D01*
X243693Y-781972D01*
X244393Y-781839D01*
X244893Y-781972D01*
X245493Y-782372D01*
G01X229193Y-829172D02*
X232993D01*
X229193Y-837172D01*
X232993D01*
G01X239093Y-831839D02*
Y-837172D01*
G01Y-829705D02*
X238893Y-829572D01*
Y-829305D01*
X239093Y-829172D01*
X239293Y-829305D01*
Y-829572D01*
X239093Y-829705D01*
G01X245793Y-834505D02*
X248393D01*
G01X253093Y-837172D02*
Y-829172D01*
X255493D01*
X256293Y-829572D01*
X256893Y-830505D01*
X257093Y-831572D01*
X256893Y-832639D01*
X256393Y-833439D01*
X255493Y-833839D01*
X253093D01*
G01X263093Y-831839D02*
Y-837172D01*
G01Y-829705D02*
X262893Y-829572D01*
Y-829305D01*
X263093Y-829172D01*
X263293Y-829305D01*
Y-829572D01*
X263093Y-829705D01*
G01X269393Y-837172D02*
Y-831839D01*
G01Y-833172D02*
X269793Y-832505D01*
X270393Y-831972D01*
X271193Y-831839D01*
X271893Y-831972D01*
X272493Y-832505D01*
X272793Y-833439D01*
Y-837172D01*
G01X277693Y-839172D02*
X278393Y-839705D01*
X279193Y-839839D01*
X279893Y-839705D01*
X280493Y-839039D01*
X280893Y-838105D01*
Y-831839D01*
G01Y-832905D02*
X280493Y-832372D01*
X279893Y-831972D01*
X279193Y-831839D01*
X278393Y-832105D01*
X277893Y-832639D01*
X277493Y-833572D01*
X277293Y-834505D01*
X277393Y-835305D01*
X277793Y-836239D01*
X278393Y-836905D01*
X279193Y-837172D01*
X279793Y-837039D01*
X280493Y-836505D01*
X280893Y-835972D01*
G01X223493Y-812172D02*
Y-804172D01*
X226093Y-810839D01*
X228693Y-804172D01*
Y-812172D01*
G01X231593D02*
X234093Y-804172D01*
X236593Y-812172D01*
G01X235693Y-809372D02*
X232493D01*
G01X239993Y-811106D02*
X240793Y-811772D01*
X241693Y-812172D01*
X242493D01*
X243293Y-811772D01*
X243893Y-811106D01*
X244193Y-810172D01*
X243993Y-809239D01*
X243493Y-808439D01*
X242593Y-807905D01*
X241393Y-807639D01*
X240693Y-807105D01*
X240393Y-806172D01*
X240593Y-805239D01*
X241093Y-804572D01*
X241793Y-804172D01*
X242493D01*
X243193Y-804439D01*
X243793Y-805105D01*
G01X247893Y-812172D02*
Y-804172D01*
G01X251693D02*
X247893Y-809106D01*
G01X252293Y-812172D02*
X249593Y-806839D01*
G01X256793Y-809505D02*
X259393D01*
G01X266893Y-807905D02*
X267293Y-807505D01*
X267593Y-806839D01*
X267793Y-805905D01*
X267593Y-805105D01*
X267193Y-804572D01*
X266493Y-804172D01*
X263793D01*
Y-812172D01*
X267093D01*
X267793Y-811639D01*
X268193Y-810839D01*
X268393Y-809905D01*
X268193Y-808972D01*
X267593Y-808172D01*
X266893Y-807905D01*
X263793D01*
G01X274093Y-812172D02*
X273293Y-812039D01*
X272593Y-811505D01*
X271993Y-810705D01*
X271593Y-809772D01*
X271393Y-808705D01*
Y-807639D01*
X271593Y-806572D01*
X271993Y-805639D01*
X272593Y-804839D01*
X273293Y-804305D01*
X274093Y-804172D01*
X274893Y-804305D01*
X275593Y-804839D01*
X276193Y-805639D01*
X276593Y-806572D01*
X276793Y-807639D01*
Y-808705D01*
X276593Y-809772D01*
X276193Y-810705D01*
X275593Y-811505D01*
X274893Y-812039D01*
X274093Y-812172D01*
G01X282093Y-804172D02*
Y-812172D01*
G01X279793Y-804172D02*
X284393D01*
G01X336693Y-830505D02*
X337293Y-829705D01*
X337993Y-829305D01*
X338793Y-829172D01*
X339793Y-829439D01*
X340493Y-830105D01*
X340693Y-830905D01*
X340593Y-831706D01*
X340193Y-832372D01*
X338193Y-833705D01*
X337293Y-834639D01*
X336693Y-835972D01*
X336493Y-837172D01*
X340693D01*
G01X346593Y-829172D02*
X345793Y-829439D01*
X345193Y-830105D01*
X344793Y-830905D01*
X344493Y-831972D01*
X344393Y-833172D01*
X344493Y-834372D01*
X344793Y-835439D01*
X345193Y-836239D01*
X345793Y-836905D01*
X346593Y-837172D01*
X347393Y-836905D01*
X347993Y-836239D01*
X348393Y-835439D01*
X348693Y-834372D01*
X348793Y-833172D01*
X348693Y-831972D01*
X348393Y-830905D01*
X347993Y-830105D01*
X347393Y-829439D01*
X346593Y-829172D01*
G01X352693Y-830505D02*
X353293Y-829705D01*
X353993Y-829305D01*
X354793Y-829172D01*
X355793Y-829439D01*
X356493Y-830105D01*
X356693Y-830905D01*
X356593Y-831706D01*
X356193Y-832372D01*
X354193Y-833705D01*
X353293Y-834639D01*
X352693Y-835972D01*
X352493Y-837172D01*
X356693D01*
G01X360693Y-830505D02*
X361293Y-829705D01*
X361993Y-829305D01*
X362793Y-829172D01*
X363793Y-829439D01*
X364493Y-830105D01*
X364693Y-830905D01*
X364593Y-831706D01*
X364193Y-832372D01*
X362193Y-833705D01*
X361293Y-834639D01*
X360693Y-835972D01*
X360493Y-837172D01*
X364693D01*
G01X368793Y-837439D02*
X372393Y-829172D01*
G01X378593Y-837172D02*
Y-829172D01*
X377393Y-830772D01*
G01Y-837172D02*
X379793D01*
G01X384693Y-830505D02*
X385293Y-829705D01*
X385993Y-829305D01*
X386793Y-829172D01*
X387793Y-829439D01*
X388493Y-830105D01*
X388693Y-830905D01*
X388593Y-831706D01*
X388193Y-832372D01*
X386193Y-833705D01*
X385293Y-834639D01*
X384693Y-835972D01*
X384493Y-837172D01*
X388693D01*
G01X392793Y-837439D02*
X396393Y-829172D01*
G01X402593D02*
X401793Y-829439D01*
X401193Y-830105D01*
X400793Y-830905D01*
X400493Y-831972D01*
X400393Y-833172D01*
X400493Y-834372D01*
X400793Y-835439D01*
X401193Y-836239D01*
X401793Y-836905D01*
X402593Y-837172D01*
X403393Y-836905D01*
X403993Y-836239D01*
X404393Y-835439D01*
X404693Y-834372D01*
X404793Y-833172D01*
X404693Y-831972D01*
X404393Y-830905D01*
X403993Y-830105D01*
X403393Y-829439D01*
X402593Y-829172D01*
G01X408693Y-830505D02*
X409293Y-829705D01*
X409993Y-829305D01*
X410793Y-829172D01*
X411793Y-829439D01*
X412493Y-830105D01*
X412693Y-830905D01*
X412593Y-831706D01*
X412193Y-832372D01*
X410193Y-833705D01*
X409293Y-834639D01*
X408693Y-835972D01*
X408493Y-837172D01*
X412693D01*
G01X336393Y-814672D02*
Y-806672D01*
X338393D01*
X339193Y-807072D01*
X339793Y-807605D01*
X340293Y-808405D01*
X340693Y-809339D01*
X340793Y-810672D01*
X340693Y-812005D01*
X340293Y-812939D01*
X339793Y-813739D01*
X339193Y-814272D01*
X338393Y-814672D01*
X336393D01*
G01X344093D02*
X346593Y-806672D01*
X349093Y-814672D01*
G01X348193Y-811872D02*
X344993D01*
G01X354593Y-806672D02*
X353793Y-806939D01*
X353193Y-807605D01*
X352793Y-808405D01*
X352493Y-809472D01*
X352393Y-810672D01*
X352493Y-811872D01*
X352793Y-812939D01*
X353193Y-813739D01*
X353793Y-814405D01*
X354593Y-814672D01*
X355393Y-814405D01*
X355993Y-813739D01*
X356393Y-812939D01*
X356693Y-811872D01*
X356793Y-810672D01*
X356693Y-809472D01*
X356393Y-808405D01*
X355993Y-807605D01*
X355393Y-806939D01*
X354593Y-806672D01*
G01X360693Y-814672D02*
Y-806672D01*
X364493D01*
G01X363093Y-810539D02*
X360693D01*
G01X370593Y-806672D02*
X369793Y-806939D01*
X369193Y-807605D01*
X368793Y-808405D01*
X368493Y-809472D01*
X368393Y-810672D01*
X368493Y-811872D01*
X368793Y-812939D01*
X369193Y-813739D01*
X369793Y-814405D01*
X370593Y-814672D01*
X371393Y-814405D01*
X371993Y-813739D01*
X372393Y-812939D01*
X372693Y-811872D01*
X372793Y-810672D01*
X372693Y-809472D01*
X372393Y-808405D01*
X371993Y-807605D01*
X371393Y-806939D01*
X370593Y-806672D01*
G01X378593D02*
Y-814672D01*
G01X376293Y-806672D02*
X380893D01*
G01X384593Y-814672D02*
Y-806672D01*
X386993D01*
X387793Y-807072D01*
X388393Y-808005D01*
X388593Y-809072D01*
X388393Y-810139D01*
X387893Y-810939D01*
X386993Y-811339D01*
X384593D01*
G01X395393Y-810405D02*
X395793Y-810005D01*
X396093Y-809339D01*
X396293Y-808405D01*
X396093Y-807605D01*
X395693Y-807072D01*
X394993Y-806672D01*
X392293D01*
Y-814672D01*
X395593D01*
X396293Y-814139D01*
X396693Y-813339D01*
X396893Y-812405D01*
X396693Y-811472D01*
X396093Y-810672D01*
X395393Y-810405D01*
X392293D01*
G01X400093Y-814672D02*
X402593Y-806672D01*
X405093Y-814672D01*
G01X404193Y-811872D02*
X400993D01*
G01X408693Y-814672D02*
Y-806672D01*
X412493D01*
G01X411093Y-810539D02*
X408693D01*
G01X418593Y-806672D02*
X417793Y-806939D01*
X417193Y-807605D01*
X416793Y-808405D01*
X416493Y-809472D01*
X416393Y-810672D01*
X416493Y-811872D01*
X416793Y-812939D01*
X417193Y-813739D01*
X417793Y-814405D01*
X418593Y-814672D01*
X419393Y-814405D01*
X419993Y-813739D01*
X420393Y-812939D01*
X420693Y-811872D01*
X420793Y-810672D01*
X420693Y-809472D01*
X420393Y-808405D01*
X419993Y-807605D01*
X419393Y-806939D01*
X418593Y-806672D01*
G01X356693Y-787172D02*
Y-779172D01*
X360493D01*
G01X359093Y-783039D02*
X356693D01*
G01X366593Y-779172D02*
X365793Y-779439D01*
X365193Y-780105D01*
X364793Y-780905D01*
X364493Y-781972D01*
X364393Y-783172D01*
X364493Y-784372D01*
X364793Y-785439D01*
X365193Y-786239D01*
X365793Y-786905D01*
X366593Y-787172D01*
X367393Y-786905D01*
X367993Y-786239D01*
X368393Y-785439D01*
X368693Y-784372D01*
X368793Y-783172D01*
X368693Y-781972D01*
X368393Y-780905D01*
X367993Y-780105D01*
X367393Y-779439D01*
X366593Y-779172D01*
G01X374593D02*
Y-787172D01*
G01X372293Y-779172D02*
X376893D01*
G01X379593Y-789839D02*
X385593D01*
G01X388593Y-787172D02*
Y-779172D01*
X390993D01*
X391793Y-779572D01*
X392393Y-780505D01*
X392593Y-781572D01*
X392393Y-782639D01*
X391893Y-783439D01*
X390993Y-783839D01*
X388593D01*
G01X396393Y-787172D02*
Y-779172D01*
X398393D01*
X399193Y-779572D01*
X399793Y-780105D01*
X400293Y-780905D01*
X400693Y-781839D01*
X400793Y-783172D01*
X400693Y-784505D01*
X400293Y-785439D01*
X399793Y-786239D01*
X399193Y-786772D01*
X398393Y-787172D01*
X396393D01*
G01X407393Y-782905D02*
X407793Y-782505D01*
X408093Y-781839D01*
X408293Y-780905D01*
X408093Y-780105D01*
X407693Y-779572D01*
X406993Y-779172D01*
X404293D01*
Y-787172D01*
X407593D01*
X408293Y-786639D01*
X408693Y-785839D01*
X408893Y-784905D01*
X408693Y-783972D01*
X408093Y-783172D01*
X407393Y-782905D01*
X404293D01*
G01X411593Y-789839D02*
X417593D01*
G01X424793Y-779839D02*
X424193Y-779439D01*
X423493Y-779172D01*
X422693D01*
X421793Y-779572D01*
X421093Y-780239D01*
X420593Y-781039D01*
X420193Y-782372D01*
X420093Y-783572D01*
X420293Y-784772D01*
X420593Y-785572D01*
X421193Y-786372D01*
X421893Y-786905D01*
X422593Y-787172D01*
X423293D01*
X423993Y-786905D01*
X424593Y-786505D01*
X425093Y-785972D01*
G01X430593Y-787172D02*
X429793Y-787039D01*
X429093Y-786505D01*
X428493Y-785705D01*
X428093Y-784772D01*
X427893Y-783705D01*
Y-782639D01*
X428093Y-781572D01*
X428493Y-780639D01*
X429093Y-779839D01*
X429793Y-779305D01*
X430593Y-779172D01*
X431393Y-779305D01*
X432093Y-779839D01*
X432693Y-780639D01*
X433093Y-781572D01*
X433293Y-782639D01*
Y-783705D01*
X433093Y-784772D01*
X432693Y-785705D01*
X432093Y-786505D01*
X431393Y-787039D01*
X430593Y-787172D01*
G01X436293D02*
Y-779172D01*
X440893Y-787172D01*
Y-779172D01*
G01X444093D02*
X446593Y-787172D01*
X449093Y-779172D01*
G01X456593Y-787172D02*
X452593D01*
Y-779172D01*
X456593D01*
G01X454993Y-783039D02*
X452593D01*
G01X460593Y-787172D02*
Y-779172D01*
X463093D01*
X463893Y-779572D01*
X464393Y-780105D01*
X464593Y-781172D01*
X464393Y-782239D01*
X463793Y-782905D01*
X463093Y-783305D01*
X460593D01*
G01X463093D02*
X464593Y-787172D01*
G01X470593Y-779172D02*
Y-787172D01*
G01X468293Y-779172D02*
X472893D01*
G01X480593Y-787172D02*
X476593D01*
Y-779172D01*
X480593D01*
G01X478993Y-783039D02*
X476593D01*
G01X484593Y-787172D02*
Y-779172D01*
X487093D01*
X487893Y-779572D01*
X488393Y-780105D01*
X488593Y-781172D01*
X488393Y-782239D01*
X487793Y-782905D01*
X487093Y-783305D01*
X484593D01*
G01X487093D02*
X488593Y-787172D01*
G01X425093Y-840172D02*
Y-832172D01*
X423893Y-833772D01*
G01Y-840172D02*
X426293D01*
G01X431193Y-836839D02*
X431893Y-835905D01*
X432493Y-835372D01*
X433293Y-835105D01*
X433993Y-835372D01*
X434493Y-835905D01*
X434893Y-836705D01*
X434993Y-837639D01*
X434893Y-838439D01*
X434493Y-839239D01*
X433893Y-839905D01*
X433193Y-840172D01*
X432393Y-839905D01*
X431693Y-839106D01*
X431293Y-837905D01*
X431193Y-836572D01*
X431393Y-834839D01*
X431693Y-833905D01*
X432193Y-832972D01*
X432893Y-832305D01*
X433593Y-832172D01*
X434293Y-832439D01*
X434793Y-833105D01*
G01X441093Y-840439D02*
X440893Y-840305D01*
Y-840039D01*
X441093Y-839905D01*
X441293Y-840039D01*
Y-840305D01*
X441093Y-840439D01*
G01X447193Y-836839D02*
X447893Y-835905D01*
X448493Y-835372D01*
X449293Y-835105D01*
X449993Y-835372D01*
X450493Y-835905D01*
X450893Y-836705D01*
X450993Y-837639D01*
X450893Y-838439D01*
X450493Y-839239D01*
X449893Y-839905D01*
X449193Y-840172D01*
X448393Y-839905D01*
X447693Y-839106D01*
X447293Y-837905D01*
X447193Y-836572D01*
X447393Y-834839D01*
X447693Y-833905D01*
X448193Y-832972D01*
X448893Y-832305D01*
X449593Y-832172D01*
X450293Y-832439D01*
X450793Y-833105D01*
G01X470093Y-840172D02*
Y-832172D01*
X468893Y-833772D01*
G01Y-840172D02*
X471293D01*
G01X477893D02*
X478093Y-838439D01*
X478393Y-836972D01*
X478793Y-835639D01*
X479293Y-834172D01*
X480093Y-832172D01*
X476093D01*
G01X486093Y-840439D02*
X485893Y-840305D01*
Y-840039D01*
X486093Y-839905D01*
X486293Y-840039D01*
Y-840305D01*
X486093Y-840439D01*
G01X492193Y-833505D02*
X492793Y-832705D01*
X493493Y-832305D01*
X494293Y-832172D01*
X495293Y-832439D01*
X495993Y-833105D01*
X496193Y-833905D01*
X496093Y-834706D01*
X495693Y-835372D01*
X493693Y-836705D01*
X492793Y-837639D01*
X492193Y-838972D01*
X491993Y-840172D01*
X496193D01*
G01X490193Y-815172D02*
Y-807172D01*
X493993D01*
G01X492593Y-811039D02*
X490193D01*
G54D48*
X831059Y349740D03*
X825941D03*
Y342260D03*
X828500D03*
X831059D03*
X905941Y309260D03*
X908500D03*
X911059D03*
Y316740D03*
X905941D03*
G54D57*
X1077500Y100563D03*
X1081240Y108437D03*
X1073760D03*
X1088000Y156937D03*
X1084260Y149063D03*
X1091740D03*
G54D39*
X268000Y240000D03*
X312500D03*
X357000D03*
X428500D03*
X472500D03*
X516500D03*
X578500D03*
X622500D03*
X666500D03*
X735981D03*
X779981D03*
X823981D03*
G54D49*
X852240Y340177D03*
X848500D03*
X844760D03*
Y349823D03*
X852240D03*
X923740Y341177D03*
X920000D03*
X916260D03*
Y350823D03*
X923740D03*
G54D58*
X1093343Y364043D03*
X1092000Y349800D03*
Y344000D03*
X1093343Y369843D03*
X1091000Y397400D03*
Y391600D03*
X1093343Y417343D03*
Y411543D03*
G54D59*
X1086243Y343943D03*
X1080443D03*
X1086243Y352443D03*
X1080443D03*
X1086243Y392500D03*
X1080443D03*
X1086243Y399943D03*
X1080443D03*
M02*
